(kicad_pcb
	(version 20260206)
	(generator "pcbnew")
	(generator_version "10.0")
	(general
		(thickness 1.6)
		(legacy_teardrops no)
	)
	(paper "A4")
	(layers
		(0 "F.Cu" signal "TOP")
		(4 "In1.Cu" signal "L2GND")
		(6 "In2.Cu" signal "L3VCC")
		(2 "B.Cu" signal "BOTTOM")
		(9 "F.Adhes" user "F.Adhesive")
		(11 "B.Adhes" user "B.Adhesive")
		(13 "F.Paste" user "Package Geometry/Pastemask Top")
		(15 "B.Paste" user "Package Geometry/Pastemask Bottom")
		(5 "F.SilkS" user "Ref Des/Silkscreen Top")
		(7 "B.SilkS" user "Ref Des/Silkscreen Bottom")
		(1 "F.Mask" user "Board Geometry/Soldermask Top")
		(3 "B.Mask" user "Board Geometry/Soldermask Bottom")
		(17 "Dwgs.User" user "User.Drawings")
		(19 "Cmts.User" user "User.Comments")
		(21 "Eco1.User" user "User.Eco1")
		(23 "Eco2.User" user "User.Eco2")
		(25 "Edge.Cuts" user "Board Geometry/Outline")
		(27 "Margin" user)
		(31 "F.CrtYd" user "Package Geometry/Place Bound Top")
		(29 "B.CrtYd" user "Package Geometry/Place Bound Bottom")
		(35 "F.Fab" user "Ref Des/Assembly Top")
		(33 "B.Fab" user "Ref Des/Assembly Bottom")
	)
	(setup
		(pad_to_mask_clearance 0)
		(allow_soldermask_bridges_in_footprints no)
		(tenting
			(front yes)
			(back yes)
		)
		(covering
			(front no)
			(back no)
		)
		(plugging
			(front no)
			(back no)
		)
		(capping no)
		(filling no)
		(pcbplotparams
			(layerselection 0x00000000_00000000_55555555_5755f5ff)
			(plot_on_all_layers_selection 0x00000000_00000000_00000000_00000000)
			(disableapertmacros no)
			(usegerberextensions no)
			(usegerberattributes yes)
			(usegerberadvancedattributes yes)
			(creategerberjobfile yes)
			(dashed_line_dash_ratio 12)
			(dashed_line_gap_ratio 3)
			(svgprecision 4)
			(plotframeref no)
			(mode 1)
			(useauxorigin no)
			(pdf_front_fp_property_popups yes)
			(pdf_back_fp_property_popups yes)
			(pdf_metadata yes)
			(pdf_single_document no)
			(dxfpolygonmode yes)
			(dxfimperialunits yes)
			(dxfusepcbnewfont yes)
			(psnegative no)
			(psa4output no)
			(plot_black_and_white yes)
			(sketchpadsonfab no)
			(plotpadnumbers no)
			(hidednponfab no)
			(sketchdnponfab yes)
			(crossoutdnponfab yes)
			(subtractmaskfromsilk no)
			(outputformat 1)
			(mirror no)
			(drillshape 1)
			(scaleselection 1)
			(outputdirectory "")
		)
	)
	(footprint ""
		(layer "F.Cu")
		(at 123.85675 -47.164244 180)
		(property "Reference" "TC3"
			(at 0 0 180)
			(layer "F.SilkS")
			(hide yes)
			(effects
				(font
					(size 1.27 1.27)
				)
			)
		)
		(property "Value" "ST68U16VDM-1-GP"
			(at 0 -9.6012 180)
			(unlocked yes)
			(layer "F.Fab")
			(hide yes)
			(effects
				(font
					(size 1.016 1.016)
					(thickness 0.1524)
				)
			)
		)
		(property "Device Type" "CT7343H79"
			(at 0 -11.1252 180)
			(unlocked yes)
			(layer "F.Fab")
			(hide yes)
			(effects
				(font
					(size 1.016 1.016)
					(thickness 0.1524)
				)
			)
		)
		(duplicate_pad_numbers_are_jumpers no)
		(fp_line
			(start 2.286 4.8768)
			(end -2.286 4.8768)
			(stroke
				(width 0.1524)
				(type default)
			)
			(layer "F.SilkS")
		)
		(fp_line
			(start 2.286 2.032)
			(end 2.286 4.8768)
			(stroke
				(width 0.1524)
				(type default)
			)
			(layer "F.SilkS")
		)
		(fp_line
			(start 2.286 -2.032)
			(end 2.286 -4.8768)
			(stroke
				(width 0.1524)
				(type default)
			)
			(layer "F.SilkS")
		)
		(fp_line
			(start 2.286 -4.8768)
			(end -2.286 -4.8768)
			(stroke
				(width 0.1524)
				(type default)
			)
			(layer "F.SilkS")
		)
		(fp_line
			(start 2.1082 -4.699)
			(end -2.1082 -4.699)
			(stroke
				(width 0.508)
				(type default)
			)
			(layer "F.SilkS")
		)
		(fp_line
			(start -2.286 4.8768)
			(end -2.286 2.032)
			(stroke
				(width 0.1524)
				(type default)
			)
			(layer "F.SilkS")
		)
		(fp_line
			(start -2.286 -4.8768)
			(end -2.286 -2.032)
			(stroke
				(width 0.1524)
				(type default)
			)
			(layer "F.SilkS")
		)
		(fp_rect
			(start -2.1463 3.6449)
			(end 2.1463 -3.6449)
			(stroke
				(width 0)
				(type default)
			)
			(fill no)
			(layer "F.CrtYd")
		)
		(fp_poly
			(pts
				(xy -2.54 4.953) (xy -2.54 4.2926) (xy -3.81 4.2926) (xy -3.81 -4.2926) (xy -2.54 -4.2926) (xy -2.54 -4.953)
				(xy 2.54 -4.953) (xy 2.54 -4.2926) (xy 3.81 -4.2926) (xy 3.81 -1.6256) (xy 2.1463 -1.6256) (xy 2.1463 -3.6449)
				(xy -2.1463 -3.6449) (xy -2.1463 3.6449) (xy 2.1463 3.6449) (xy 2.1463 -1.6129) (xy 3.81 -1.6129)
				(xy 3.81 4.2926) (xy 2.54 4.2926) (xy 2.54 4.953)
			)
			(stroke
				(width 0)
				(type default)
			)
			(fill no)
			(layer "F.CrtYd")
		)
		(fp_rect
			(start 2.54 4.2926)
			(end 3.81 -4.2926)
			(stroke
				(width 0)
				(type default)
			)
			(fill no)
			(layer "F.Fab")
		)
		(fp_rect
			(start -2.54 4.953)
			(end 2.54 -4.953)
			(stroke
				(width 0)
				(type default)
			)
			(fill no)
			(layer "F.Fab")
		)
		(fp_rect
			(start -3.81 4.2926)
			(end -2.54 -4.2926)
			(stroke
				(width 0)
				(type default)
			)
			(fill no)
			(layer "F.Fab")
		)
		(pad "1" smd rect
			(at 0 -3.1496 180)
			(size 2.413 2.286)
			(layers "F.Cu" "F.Mask" "F.Paste")
			(net "P12V")
		)
		(pad "2" smd rect
			(at 0 3.1496 180)
			(size 2.413 2.286)
			(layers "F.Cu" "F.Mask" "F.Paste")
			(net "GND")
		)
		(zone
			(layer "F.Cu")
			(hatch none 0.5)
			(connect_pads
				(clearance 0)
			)
			(min_thickness 0.25)
			(keepout
				(tracks allowed)
				(vias not_allowed)
				(pads allowed)
				(copperpour not_allowed)
				(footprints allowed)
			)
			(placement
				(enabled no)
				(sheetname "")
			)
			(fill
				(thermal_gap 0.5)
				(thermal_bridge_width 0.5)
				(island_removal_mode 0)
			)
			(polygon
				(pts
					(xy 122.34545 -45.475144) (xy 122.34545 -42.566844) (xy 125.36805 -42.566844) (xy 125.36805 -45.462444)
					(xy 125.36805 -45.792644) (xy 122.34545 -45.792644)
				)
			)
		)
		(zone
			(layer "F.Cu")
			(hatch none 0.5)
			(connect_pads
				(clearance 0)
			)
			(min_thickness 0.25)
			(keepout
				(tracks allowed)
				(vias not_allowed)
				(pads allowed)
				(copperpour not_allowed)
				(footprints allowed)
			)
			(placement
				(enabled no)
				(sheetname "")
			)
			(fill
				(thermal_gap 0.5)
				(thermal_bridge_width 0.5)
				(island_removal_mode 0)
			)
			(polygon
				(pts
					(xy 125.36805 -51.761644) (xy 122.34545 -51.761644) (xy 122.34545 -48.866044) (xy 122.34545 -48.535844)
					(xy 125.36805 -48.535844) (xy 125.36805 -48.866044)
				)
			)
		)
	)
	(footprint ""
		(layer "F.Cu")
		(at 136.152382 -67.048634 90)
		(property "Reference" "R387"
			(at 0 0 90)
			(layer "F.SilkS")
			(hide yes)
			(effects
				(font
					(size 1.27 1.27)
				)
			)
		)
		(property "Value" "0R2J-2-GP"
			(at 0.064008 -3.993896 90)
			(unlocked yes)
			(layer "F.Fab")
			(hide yes)
			(effects
				(font
					(size 1.016 1.016)
					(thickness 0.1524)
				)
			)
		)
		(property "Device Type" "R402H16"
			(at 0.064008 -5.517896 90)
			(unlocked yes)
			(layer "F.Fab")
			(hide yes)
			(effects
				(font
					(size 1.016 1.016)
					(thickness 0.1524)
				)
			)
		)
		(duplicate_pad_numbers_are_jumpers no)
		(fp_line
			(start 0.508 -0.9398)
			(end -0.508 -0.9398)
			(stroke
				(width 0.1524)
				(type default)
			)
			(layer "F.SilkS")
		)
		(fp_line
			(start -0.508 -0.9398)
			(end -0.508 0.9398)
			(stroke
				(width 0.1524)
				(type default)
			)
			(layer "F.SilkS")
		)
		(fp_rect
			(start -0.508 0.9398)
			(end 0.508 -0.9398)
			(stroke
				(width 0)
				(type default)
			)
			(fill no)
			(layer "F.CrtYd")
		)
		(fp_rect
			(start -0.508 0.9398)
			(end 0.508 -0.9398)
			(stroke
				(width 0)
				(type default)
			)
			(fill no)
			(layer "F.Fab")
		)
		(pad "1" smd custom
			(at 0 -0.4445 90)
			(size 0.1397 0.1397)
			(layers "F.Cu" "F.Mask" "F.Paste")
			(net "I2C_C_BUF_SCL")
			(options
				(clearance outline)
				(anchor circle)
			)
			(primitives
				(gr_poly
					(pts
						(arc
							(start -0.1778 -0.2794)
							(mid -0.249642 -0.249642)
							(end -0.2794 -0.1778)
						)
						(arc
							(start -0.2794 0.1778)
							(mid -0.249642 0.249642)
							(end -0.1778 0.2794)
						)
						(arc
							(start 0.1778 0.2794)
							(mid 0.249642 0.249642)
							(end 0.2794 0.1778)
						)
						(arc
							(start 0.2794 -0.1778)
							(mid 0.249642 -0.249642)
							(end 0.1778 -0.2794)
						)
					)
					(width 0)
					(fill yes)
				)
			)
		)
		(pad "2" smd custom
			(at 0 0.4445 90)
			(size 0.1397 0.1397)
			(layers "F.Cu" "F.Mask" "F.Paste")
			(net "I2C_C_BUF_SCL_CONN")
			(options
				(clearance outline)
				(anchor circle)
			)
			(primitives
				(gr_poly
					(pts
						(arc
							(start -0.1778 -0.2794)
							(mid -0.249642 -0.249642)
							(end -0.2794 -0.1778)
						)
						(arc
							(start -0.2794 0.1778)
							(mid -0.249642 0.249642)
							(end -0.1778 0.2794)
						)
						(arc
							(start 0.1778 0.2794)
							(mid 0.249642 0.249642)
							(end 0.2794 0.1778)
						)
						(arc
							(start 0.2794 -0.1778)
							(mid 0.249642 -0.249642)
							(end 0.1778 -0.2794)
						)
					)
					(width 0)
					(fill yes)
				)
			)
		)
	)
	(footprint ""
		(layer "F.Cu")
		(at 9.679686 -92.946982)
		(property "Reference" "C358"
			(at 0 0 0)
			(layer "F.SilkS")
			(hide yes)
			(effects
				(font
					(size 1.27 1.27)
				)
			)
		)
		(property "Value" "SC220P50V3JN-GP"
			(at 0 -2.8194 0)
			(unlocked yes)
			(layer "F.Fab")
			(hide yes)
			(effects
				(font
					(size 1.016 1.016)
					(thickness 0.1524)
				)
			)
		)
		(property "Device Type" "C603H36"
			(at 0 -4.3434 0)
			(unlocked yes)
			(layer "F.Fab")
			(hide yes)
			(effects
				(font
					(size 1.016 1.016)
					(thickness 0.1524)
				)
			)
		)
		(duplicate_pad_numbers_are_jumpers no)
		(fp_line
			(start 0.508 0)
			(end -0.508 0)
			(stroke
				(width 0.2032)
				(type default)
			)
			(layer "F.SilkS")
		)
		(fp_rect
			(start -0.5842 1.3335)
			(end 0.5842 -1.3335)
			(stroke
				(width 0)
				(type default)
			)
			(fill no)
			(layer "F.CrtYd")
		)
		(fp_rect
			(start -0.5842 1.3335)
			(end 0.5842 -1.3335)
			(stroke
				(width 0)
				(type default)
			)
			(fill no)
			(layer "F.Fab")
		)
		(pad "1" smd custom
			(at 0 -0.762)
			(size 0.2159 0.2159)
			(layers "F.Cu" "F.Mask" "F.Paste")
			(net "I2C_C_SCL")
			(options
				(clearance outline)
				(anchor circle)
			)
			(primitives
				(gr_poly
					(pts
						(arc
							(start -0.3302 -0.4318)
							(mid -0.402042 -0.402042)
							(end -0.4318 -0.3302)
						)
						(arc
							(start -0.4318 0.3302)
							(mid -0.402042 0.402042)
							(end -0.3302 0.4318)
						)
						(arc
							(start 0.3302 0.4318)
							(mid 0.402042 0.402042)
							(end 0.4318 0.3302)
						)
						(arc
							(start 0.4318 -0.3302)
							(mid 0.402042 -0.402042)
							(end 0.3302 -0.4318)
						)
					)
					(width 0)
					(fill yes)
				)
			)
		)
		(pad "2" smd custom
			(at 0 0.762)
			(size 0.2159 0.2159)
			(layers "F.Cu" "F.Mask" "F.Paste")
			(net "GND")
			(options
				(clearance outline)
				(anchor circle)
			)
			(primitives
				(gr_poly
					(pts
						(arc
							(start -0.3302 -0.4318)
							(mid -0.402042 -0.402042)
							(end -0.4318 -0.3302)
						)
						(arc
							(start -0.4318 0.3302)
							(mid -0.402042 0.402042)
							(end -0.3302 0.4318)
						)
						(arc
							(start 0.3302 0.4318)
							(mid 0.402042 0.402042)
							(end 0.4318 0.3302)
						)
						(arc
							(start 0.4318 -0.3302)
							(mid 0.402042 -0.402042)
							(end 0.3302 -0.4318)
						)
					)
					(width 0)
					(fill yes)
				)
			)
		)
	)
	(footprint ""
		(layer "F.Cu")
		(at 155.66009 -98.799904 90)
		(property "Reference" "Q31"
			(at 0 0 90)
			(layer "F.SilkS")
			(hide yes)
			(effects
				(font
					(size 1.27 1.27)
				)
			)
		)
		(property "Value" "SENSOR-2P-GP-U"
			(at -3.4036 1.3462 90)
			(unlocked yes)
			(layer "F.Fab")
			(hide yes)
			(effects
				(font
					(size 1.016 1.016)
					(thickness 0.1524)
				)
			)
		)
		(property "Device Type" "SNR2N4036-UH166"
			(at -3.4036 -0.1778 90)
			(unlocked yes)
			(layer "F.Fab")
			(hide yes)
			(effects
				(font
					(size 1.016 1.016)
					(thickness 0.1524)
				)
			)
		)
		(duplicate_pad_numbers_are_jumpers no)
		(fp_line
			(start 2.0574 -2.6543)
			(end -2.1844 -2.6543)
			(stroke
				(width 0.1524)
				(type default)
			)
			(layer "F.SilkS")
		)
		(fp_line
			(start -2.1844 -2.6543)
			(end -2.1844 2.6543)
			(stroke
				(width 0.1524)
				(type default)
			)
			(layer "F.SilkS")
		)
		(fp_line
			(start 2.0574 2.6543)
			(end 2.0574 -2.6543)
			(stroke
				(width 0.1524)
				(type default)
			)
			(layer "F.SilkS")
		)
		(fp_line
			(start -2.1844 2.6543)
			(end 2.0574 2.6543)
			(stroke
				(width 0.1524)
				(type default)
			)
			(layer "F.SilkS")
		)
		(fp_poly
			(pts
				(xy -2.2098 2.0066) (xy -2.2098 1.3208) (xy -2.8702 1.3208) (xy -2.8702 2.0066)
			)
			(stroke
				(width 0)
				(type default)
			)
			(fill yes)
			(layer "F.SilkS")
		)
		(fp_rect
			(start -1.8034 1.9939)
			(end 1.8034 -1.9939)
			(stroke
				(width 0)
				(type default)
			)
			(fill no)
			(layer "F.CrtYd")
		)
		(fp_poly
			(pts
				(xy -2.4384 2.7305) (xy -2.4384 -2.7305) (xy 2.3114 -2.7305) (xy 2.3114 1.98882) (xy 1.8034 1.98882)
				(xy 1.8034 -1.9939) (xy -1.8034 -1.9939) (xy -1.8034 1.9939) (xy 2.3114 1.9939) (xy 2.3114 2.7305)
			)
			(stroke
				(width 0)
				(type default)
			)
			(fill no)
			(layer "F.CrtYd")
		)
		(fp_rect
			(start -2.4384 2.7305)
			(end 2.3114 -2.7305)
			(stroke
				(width 0)
				(type default)
			)
			(fill no)
			(layer "F.Fab")
		)
		(fp_text user "E"
			(at 2.038096 -3.71729 90)
			(unlocked yes)
			(layer "F.SilkS")
			(effects
				(font
					(size 1.016 1.016)
					(thickness 0.1524)
				)
			)
		)
		(fp_text user "C"
			(at 2.038096 3.64871 90)
			(unlocked yes)
			(layer "F.SilkS")
			(effects
				(font
					(size 1.016 1.016)
					(thickness 0.1524)
				)
			)
		)
		(pad "C" smd rect
			(at -0.374904 1.455674 90)
			(size 3.0988 1.8796)
			(layers "F.Cu" "F.Mask" "F.Paste")
			(net "DETECTOR_C")
		)
		(pad "E" smd rect
			(at -0.374904 -1.455674 90)
			(size 3.0988 1.8796)
			(layers "F.Cu" "F.Mask" "F.Paste")
			(net "IR_SWITCH_E")
		)
	)
	(footprint ""
		(layer "F.Cu")
		(at 138.684 -106.426 -90)
		(property "Reference" "R390"
			(at 0 0 270)
			(layer "F.SilkS")
			(hide yes)
			(effects
				(font
					(size 1.27 1.27)
				)
			)
		)
		(property "Value" "0R2J-2-GP"
			(at 0.064008 -3.993896 270)
			(unlocked yes)
			(layer "F.Fab")
			(hide yes)
			(effects
				(font
					(size 1.016 1.016)
					(thickness 0.1524)
				)
			)
		)
		(property "Device Type" "R402H16"
			(at 0.064008 -5.517896 270)
			(unlocked yes)
			(layer "F.Fab")
			(hide yes)
			(effects
				(font
					(size 1.016 1.016)
					(thickness 0.1524)
				)
			)
		)
		(duplicate_pad_numbers_are_jumpers no)
		(fp_line
			(start -0.508 -0.9398)
			(end -0.508 0.9398)
			(stroke
				(width 0.1524)
				(type default)
			)
			(layer "F.SilkS")
		)
		(fp_line
			(start 0.508 -0.9398)
			(end -0.508 -0.9398)
			(stroke
				(width 0.1524)
				(type default)
			)
			(layer "F.SilkS")
		)
		(fp_rect
			(start -0.508 0.9398)
			(end 0.508 -0.9398)
			(stroke
				(width 0)
				(type default)
			)
			(fill no)
			(layer "F.CrtYd")
		)
		(fp_rect
			(start -0.508 0.9398)
			(end 0.508 -0.9398)
			(stroke
				(width 0)
				(type default)
			)
			(fill no)
			(layer "F.Fab")
		)
		(pad "1" smd custom
			(at 0 -0.4445 270)
			(size 0.1397 0.1397)
			(layers "F.Cu" "F.Mask" "F.Paste")
			(net "TPS2490_DISABLE")
			(options
				(clearance outline)
				(anchor circle)
			)
			(primitives
				(gr_poly
					(pts
						(arc
							(start -0.1778 -0.2794)
							(mid -0.249642 -0.249642)
							(end -0.2794 -0.1778)
						)
						(arc
							(start -0.2794 0.1778)
							(mid -0.249642 0.249642)
							(end -0.1778 0.2794)
						)
						(arc
							(start 0.1778 0.2794)
							(mid 0.249642 0.249642)
							(end 0.2794 0.1778)
						)
						(arc
							(start 0.2794 -0.1778)
							(mid 0.249642 -0.249642)
							(end 0.1778 -0.2794)
						)
					)
					(width 0)
					(fill yes)
				)
			)
		)
		(pad "2" smd custom
			(at 0 0.4445 270)
			(size 0.1397 0.1397)
			(layers "F.Cu" "F.Mask" "F.Paste")
			(net "GND")
			(options
				(clearance outline)
				(anchor circle)
			)
			(primitives
				(gr_poly
					(pts
						(arc
							(start -0.1778 -0.2794)
							(mid -0.249642 -0.249642)
							(end -0.2794 -0.1778)
						)
						(arc
							(start -0.2794 0.1778)
							(mid -0.249642 0.249642)
							(end -0.1778 0.2794)
						)
						(arc
							(start 0.1778 0.2794)
							(mid 0.249642 0.249642)
							(end 0.2794 0.1778)
						)
						(arc
							(start 0.2794 -0.1778)
							(mid 0.249642 -0.249642)
							(end 0.1778 -0.2794)
						)
					)
					(width 0)
					(fill yes)
				)
			)
		)
	)
	(footprint ""
		(layer "F.Cu")
		(at 10.492486 -98.872802 180)
		(property "Reference" "C345"
			(at 0 0 180)
			(layer "F.SilkS")
			(hide yes)
			(effects
				(font
					(size 1.27 1.27)
				)
			)
		)
		(property "Value" "SCD01U50V2KX-1GP"
			(at 1.1811 -2.7051 180)
			(unlocked yes)
			(layer "F.Fab")
			(hide yes)
			(effects
				(font
					(size 1.016 1.016)
					(thickness 0.1524)
				)
			)
		)
		(property "Device Type" "C402H22"
			(at 1.1811 -4.2291 180)
			(unlocked yes)
			(layer "F.Fab")
			(hide yes)
			(effects
				(font
					(size 1.016 1.016)
					(thickness 0.1524)
				)
			)
		)
		(duplicate_pad_numbers_are_jumpers no)
		(fp_rect
			(start -0.4318 0.9525)
			(end 0.4318 -0.9525)
			(stroke
				(width 0)
				(type default)
			)
			(fill no)
			(layer "F.CrtYd")
		)
		(fp_rect
			(start -0.4318 0.9525)
			(end 0.4318 -0.9525)
			(stroke
				(width 0)
				(type default)
			)
			(fill no)
			(layer "F.Fab")
		)
		(pad "1" smd custom
			(at 0 -0.4445 180)
			(size 0.1524 0.1524)
			(layers "F.Cu" "F.Mask" "F.Paste")
			(net "P3V3")
			(options
				(clearance outline)
				(anchor circle)
			)
			(primitives
				(gr_poly
					(pts
						(arc
							(start 0.3048 -0.2032)
							(mid 0.275042 -0.275042)
							(end 0.2032 -0.3048)
						)
						(arc
							(start -0.2032 -0.3048)
							(mid -0.275042 -0.275042)
							(end -0.3048 -0.2032)
						)
						(arc
							(start -0.3048 0.2032)
							(mid -0.275042 0.275042)
							(end -0.2032 0.3048)
						)
						(arc
							(start 0.2032 0.3048)
							(mid 0.275042 0.275042)
							(end 0.3048 0.2032)
						)
					)
					(width 0)
					(fill yes)
				)
			)
		)
		(pad "2" smd custom
			(at 0 0.4445 180)
			(size 0.1524 0.1524)
			(layers "F.Cu" "F.Mask" "F.Paste")
			(net "GND")
			(options
				(clearance outline)
				(anchor circle)
			)
			(primitives
				(gr_poly
					(pts
						(arc
							(start 0.3048 -0.2032)
							(mid 0.275042 -0.275042)
							(end 0.2032 -0.3048)
						)
						(arc
							(start -0.2032 -0.3048)
							(mid -0.275042 -0.275042)
							(end -0.3048 -0.2032)
						)
						(arc
							(start -0.3048 0.2032)
							(mid -0.275042 0.275042)
							(end -0.2032 0.3048)
						)
						(arc
							(start 0.2032 0.3048)
							(mid 0.275042 0.275042)
							(end 0.3048 0.2032)
						)
					)
					(width 0)
					(fill yes)
				)
			)
		)
	)
	(footprint ""
		(layer "F.Cu")
		(at 139.826492 -82.838544)
		(property "Reference" "R378"
			(at 0 0 0)
			(layer "F.SilkS")
			(hide yes)
			(effects
				(font
					(size 1.27 1.27)
				)
			)
		)
		(property "Value" "68R5J-GP"
			(at 0 -8.9535 0)
			(unlocked yes)
			(layer "F.Fab")
			(hide yes)
			(effects
				(font
					(size 1.27 1.016)
					(thickness 0.1524)
				)
			)
		)
		(property "Device Type" "R805H24"
			(at 0 -10.6299 0)
			(unlocked yes)
			(layer "F.Fab")
			(hide yes)
			(effects
				(font
					(size 1.27 1.016)
					(thickness 0.1524)
				)
			)
		)
		(duplicate_pad_numbers_are_jumpers no)
		(fp_line
			(start -0.889 -1.7018)
			(end -0.889 0.2794)
			(stroke
				(width 0.1524)
				(type default)
			)
			(layer "F.SilkS")
		)
		(fp_line
			(start -0.889 0.0762)
			(end -0.889 1.7018)
			(stroke
				(width 0.1524)
				(type default)
			)
			(layer "F.SilkS")
		)
		(fp_line
			(start -0.889 1.7018)
			(end 0.889 1.7018)
			(stroke
				(width 0.1524)
				(type default)
			)
			(layer "F.SilkS")
		)
		(fp_line
			(start 0.889 -1.7018)
			(end -0.889 -1.7018)
			(stroke
				(width 0.1524)
				(type default)
			)
			(layer "F.SilkS")
		)
		(fp_line
			(start 0.889 -1.7018)
			(end 0.889 -0.381)
			(stroke
				(width 0.1524)
				(type default)
			)
			(layer "F.SilkS")
		)
		(fp_line
			(start 0.889 1.7018)
			(end 0.889 -0.508)
			(stroke
				(width 0.1524)
				(type default)
			)
			(layer "F.SilkS")
		)
		(fp_poly
			(pts
				(xy 0.9652 -1.778) (xy 0.9652 1.778) (xy -0.9652 1.778) (xy -0.9652 -1.778)
			)
			(stroke
				(width 0)
				(type default)
			)
			(fill no)
			(layer "F.CrtYd")
		)
		(fp_rect
			(start -0.9652 1.778)
			(end 0.9652 -1.778)
			(stroke
				(width 0)
				(type default)
			)
			(fill no)
			(layer "F.Fab")
		)
		(pad "1" smd rect
			(at 0 -0.9652)
			(size 1.397 1.143)
			(layers "F.Cu" "F.Mask" "F.Paste")
			(net "EMITTER_K")
		)
		(pad "2" smd rect
			(at 0 0.9652)
			(size 1.397 1.143)
			(layers "F.Cu" "F.Mask" "F.Paste")
			(net "GND")
		)
	)
	(footprint ""
		(layer "F.Cu")
		(at 107.061 -47.371 180)
		(property "Reference" "C364"
			(at 0 0 180)
			(layer "F.SilkS")
			(hide yes)
			(effects
				(font
					(size 1.27 1.27)
				)
			)
		)
		(property "Value" "SC47U16V0MX-GP"
			(at -0.00254 -4.78536 180)
			(unlocked yes)
			(layer "F.Fab")
			(hide yes)
			(effects
				(font
					(size 1.016 1.016)
					(thickness 0.1524)
				)
			)
		)
		(property "Device Type" "C1210H107"
			(at -0.00254 -6.38048 180)
			(unlocked yes)
			(layer "F.Fab")
			(hide yes)
			(effects
				(font
					(size 1.016 1.016)
					(thickness 0.1524)
				)
			)
		)
		(duplicate_pad_numbers_are_jumpers no)
		(fp_line
			(start 1.5748 2.3368)
			(end 1.5748 0.762)
			(stroke
				(width 0.1524)
				(type default)
			)
			(layer "F.SilkS")
		)
		(fp_line
			(start 1.5748 -0.762)
			(end 1.5748 -2.3368)
			(stroke
				(width 0.1524)
				(type default)
			)
			(layer "F.SilkS")
		)
		(fp_line
			(start 1.5748 -2.3368)
			(end -1.5748 -2.3368)
			(stroke
				(width 0.1524)
				(type default)
			)
			(layer "F.SilkS")
		)
		(fp_line
			(start -1.5748 2.3368)
			(end 1.5748 2.3368)
			(stroke
				(width 0.1524)
				(type default)
			)
			(layer "F.SilkS")
		)
		(fp_line
			(start -1.5748 0.762)
			(end -1.5748 2.3368)
			(stroke
				(width 0.1524)
				(type default)
			)
			(layer "F.SilkS")
		)
		(fp_line
			(start -1.5748 -2.3368)
			(end -1.5748 -0.762)
			(stroke
				(width 0.1524)
				(type default)
			)
			(layer "F.SilkS")
		)
		(fp_rect
			(start -1.651 2.413)
			(end 1.651 -2.413)
			(stroke
				(width 0)
				(type default)
			)
			(fill no)
			(layer "F.CrtYd")
		)
		(fp_poly
			(pts
				(xy 1.651 2.413) (xy 1.651 -2.413) (xy -1.651 -2.413) (xy -1.651 2.413)
			)
			(stroke
				(width 0)
				(type default)
			)
			(fill no)
			(layer "F.Fab")
		)
		(pad "1" smd rect
			(at 0 -1.4732 180)
			(size 2.794 1.397)
			(layers "F.Cu" "F.Mask" "F.Paste")
			(net "P12V")
		)
		(pad "2" smd rect
			(at 0 1.4732 180)
			(size 2.794 1.397)
			(layers "F.Cu" "F.Mask" "F.Paste")
			(net "GND")
		)
	)
	(footprint ""
		(layer "F.Cu")
		(at 8.079232 -93.708728 90)
		(property "Reference" "R389"
			(at 0 0 90)
			(layer "F.SilkS")
			(hide yes)
			(effects
				(font
					(size 1.27 1.27)
				)
			)
		)
		(property "Value" "0R2J-2-GP"
			(at 0.064008 -3.993896 90)
			(unlocked yes)
			(layer "F.Fab")
			(hide yes)
			(effects
				(font
					(size 1.016 1.016)
					(thickness 0.1524)
				)
			)
		)
		(property "Device Type" "R402H16"
			(at 0.064008 -5.517896 90)
			(unlocked yes)
			(layer "F.Fab")
			(hide yes)
			(effects
				(font
					(size 1.016 1.016)
					(thickness 0.1524)
				)
			)
		)
		(duplicate_pad_numbers_are_jumpers no)
		(fp_line
			(start 0.508 -0.9398)
			(end -0.508 -0.9398)
			(stroke
				(width 0.1524)
				(type default)
			)
			(layer "F.SilkS")
		)
		(fp_line
			(start -0.508 -0.9398)
			(end -0.508 0.9398)
			(stroke
				(width 0.1524)
				(type default)
			)
			(layer "F.SilkS")
		)
		(fp_rect
			(start -0.508 0.9398)
			(end 0.508 -0.9398)
			(stroke
				(width 0)
				(type default)
			)
			(fill no)
			(layer "F.CrtYd")
		)
		(fp_rect
			(start -0.508 0.9398)
			(end 0.508 -0.9398)
			(stroke
				(width 0)
				(type default)
			)
			(fill no)
			(layer "F.Fab")
		)
		(pad "1" smd custom
			(at 0 -0.4445 90)
			(size 0.1397 0.1397)
			(layers "F.Cu" "F.Mask" "F.Paste")
			(net "STRADDLE_I2C_C_SCL")
			(options
				(clearance outline)
				(anchor circle)
			)
			(primitives
				(gr_poly
					(pts
						(arc
							(start -0.1778 -0.2794)
							(mid -0.249642 -0.249642)
							(end -0.2794 -0.1778)
						)
						(arc
							(start -0.2794 0.1778)
							(mid -0.249642 0.249642)
							(end -0.1778 0.2794)
						)
						(arc
							(start 0.1778 0.2794)
							(mid 0.249642 0.249642)
							(end 0.2794 0.1778)
						)
						(arc
							(start 0.2794 -0.1778)
							(mid 0.249642 -0.249642)
							(end 0.1778 -0.2794)
						)
					)
					(width 0)
					(fill yes)
				)
			)
		)
		(pad "2" smd custom
			(at 0 0.4445 90)
			(size 0.1397 0.1397)
			(layers "F.Cu" "F.Mask" "F.Paste")
			(net "I2C_C_SCL")
			(options
				(clearance outline)
				(anchor circle)
			)
			(primitives
				(gr_poly
					(pts
						(arc
							(start -0.1778 -0.2794)
							(mid -0.249642 -0.249642)
							(end -0.2794 -0.1778)
						)
						(arc
							(start -0.2794 0.1778)
							(mid -0.249642 0.249642)
							(end -0.1778 0.2794)
						)
						(arc
							(start 0.1778 0.2794)
							(mid 0.249642 0.249642)
							(end 0.2794 0.1778)
						)
						(arc
							(start 0.2794 -0.1778)
							(mid 0.249642 -0.249642)
							(end 0.1778 -0.2794)
						)
					)
					(width 0)
					(fill yes)
				)
			)
		)
	)
	(footprint ""
		(layer "F.Cu")
		(at 110.49 -47.371 180)
		(property "Reference" "C363"
			(at 0 0 180)
			(layer "F.SilkS")
			(hide yes)
			(effects
				(font
					(size 1.27 1.27)
				)
			)
		)
		(property "Value" "SC47U16V0MX-GP"
			(at -0.00254 -4.78536 180)
			(unlocked yes)
			(layer "F.Fab")
			(hide yes)
			(effects
				(font
					(size 1.016 1.016)
					(thickness 0.1524)
				)
			)
		)
		(property "Device Type" "C1210H107"
			(at -0.00254 -6.38048 180)
			(unlocked yes)
			(layer "F.Fab")
			(hide yes)
			(effects
				(font
					(size 1.016 1.016)
					(thickness 0.1524)
				)
			)
		)
		(duplicate_pad_numbers_are_jumpers no)
		(fp_line
			(start 1.5748 2.3368)
			(end 1.5748 0.762)
			(stroke
				(width 0.1524)
				(type default)
			)
			(layer "F.SilkS")
		)
		(fp_line
			(start 1.5748 -0.762)
			(end 1.5748 -2.3368)
			(stroke
				(width 0.1524)
				(type default)
			)
			(layer "F.SilkS")
		)
		(fp_line
			(start 1.5748 -2.3368)
			(end -1.5748 -2.3368)
			(stroke
				(width 0.1524)
				(type default)
			)
			(layer "F.SilkS")
		)
		(fp_line
			(start -1.5748 2.3368)
			(end 1.5748 2.3368)
			(stroke
				(width 0.1524)
				(type default)
			)
			(layer "F.SilkS")
		)
		(fp_line
			(start -1.5748 0.762)
			(end -1.5748 2.3368)
			(stroke
				(width 0.1524)
				(type default)
			)
			(layer "F.SilkS")
		)
		(fp_line
			(start -1.5748 -2.3368)
			(end -1.5748 -0.762)
			(stroke
				(width 0.1524)
				(type default)
			)
			(layer "F.SilkS")
		)
		(fp_rect
			(start -1.651 2.413)
			(end 1.651 -2.413)
			(stroke
				(width 0)
				(type default)
			)
			(fill no)
			(layer "F.CrtYd")
		)
		(fp_poly
			(pts
				(xy 1.651 2.413) (xy 1.651 -2.413) (xy -1.651 -2.413) (xy -1.651 2.413)
			)
			(stroke
				(width 0)
				(type default)
			)
			(fill no)
			(layer "F.Fab")
		)
		(pad "1" smd rect
			(at 0 -1.4732 180)
			(size 2.794 1.397)
			(layers "F.Cu" "F.Mask" "F.Paste")
			(net "P12V")
		)
		(pad "2" smd rect
			(at 0 1.4732 180)
			(size 2.794 1.397)
			(layers "F.Cu" "F.Mask" "F.Paste")
			(net "GND")
		)
	)
	(footprint ""
		(layer "F.Cu")
		(at 13.38707 -89.94013 180)
		(property "Reference" "R342"
			(at 0 0 180)
			(layer "F.SilkS")
			(hide yes)
			(effects
				(font
					(size 1.27 1.27)
				)
			)
		)
		(property "Value" "10KR2F-2-GP"
			(at 0.064008 -3.993896 180)
			(unlocked yes)
			(layer "F.Fab")
			(hide yes)
			(effects
				(font
					(size 1.016 1.016)
					(thickness 0.1524)
				)
			)
		)
		(property "Device Type" "R402H16"
			(at 0.064008 -5.517896 180)
			(unlocked yes)
			(layer "F.Fab")
			(hide yes)
			(effects
				(font
					(size 1.016 1.016)
					(thickness 0.1524)
				)
			)
		)
		(duplicate_pad_numbers_are_jumpers no)
		(fp_line
			(start 0.508 -0.9398)
			(end -0.508 -0.9398)
			(stroke
				(width 0.1524)
				(type default)
			)
			(layer "F.SilkS")
		)
		(fp_line
			(start -0.508 -0.9398)
			(end -0.508 0.9398)
			(stroke
				(width 0.1524)
				(type default)
			)
			(layer "F.SilkS")
		)
		(fp_rect
			(start -0.508 0.9398)
			(end 0.508 -0.9398)
			(stroke
				(width 0)
				(type default)
			)
			(fill no)
			(layer "F.CrtYd")
		)
		(fp_rect
			(start -0.508 0.9398)
			(end 0.508 -0.9398)
			(stroke
				(width 0)
				(type default)
			)
			(fill no)
			(layer "F.Fab")
		)
		(pad "1" smd custom
			(at 0 -0.4445 180)
			(size 0.1397 0.1397)
			(layers "F.Cu" "F.Mask" "F.Paste")
			(net "P3V3")
			(options
				(clearance outline)
				(anchor circle)
			)
			(primitives
				(gr_poly
					(pts
						(arc
							(start -0.1778 -0.2794)
							(mid -0.249642 -0.249642)
							(end -0.2794 -0.1778)
						)
						(arc
							(start -0.2794 0.1778)
							(mid -0.249642 0.249642)
							(end -0.1778 0.2794)
						)
						(arc
							(start 0.1778 0.2794)
							(mid 0.249642 0.249642)
							(end 0.2794 0.1778)
						)
						(arc
							(start 0.2794 -0.1778)
							(mid 0.249642 -0.249642)
							(end 0.1778 -0.2794)
						)
					)
					(width 0)
					(fill yes)
				)
			)
		)
		(pad "2" smd custom
			(at 0 0.4445 180)
			(size 0.1397 0.1397)
			(layers "F.Cu" "F.Mask" "F.Paste")
			(net "I2C_C_BUF_SCLOUT")
			(options
				(clearance outline)
				(anchor circle)
			)
			(primitives
				(gr_poly
					(pts
						(arc
							(start -0.1778 -0.2794)
							(mid -0.249642 -0.249642)
							(end -0.2794 -0.1778)
						)
						(arc
							(start -0.2794 0.1778)
							(mid -0.249642 0.249642)
							(end -0.1778 0.2794)
						)
						(arc
							(start 0.1778 0.2794)
							(mid 0.249642 0.249642)
							(end 0.2794 0.1778)
						)
						(arc
							(start 0.2794 -0.1778)
							(mid 0.249642 -0.249642)
							(end 0.1778 -0.2794)
						)
					)
					(width 0)
					(fill yes)
				)
			)
		)
	)
	(footprint ""
		(layer "F.Cu")
		(at 12.977876 -98.81235)
		(property "Reference" "R344"
			(at 0 0 0)
			(layer "F.SilkS")
			(hide yes)
			(effects
				(font
					(size 1.27 1.27)
				)
			)
		)
		(property "Value" "10KR2F-2-GP"
			(at 0.064008 -3.993896 0)
			(unlocked yes)
			(layer "F.Fab")
			(hide yes)
			(effects
				(font
					(size 1.016 1.016)
					(thickness 0.1524)
				)
			)
		)
		(property "Device Type" "R402H16"
			(at 0.064008 -5.517896 0)
			(unlocked yes)
			(layer "F.Fab")
			(hide yes)
			(effects
				(font
					(size 1.016 1.016)
					(thickness 0.1524)
				)
			)
		)
		(duplicate_pad_numbers_are_jumpers no)
		(fp_line
			(start -0.508 -0.9398)
			(end -0.508 0.9398)
			(stroke
				(width 0.1524)
				(type default)
			)
			(layer "F.SilkS")
		)
		(fp_line
			(start 0.508 -0.9398)
			(end -0.508 -0.9398)
			(stroke
				(width 0.1524)
				(type default)
			)
			(layer "F.SilkS")
		)
		(fp_rect
			(start -0.508 0.9398)
			(end 0.508 -0.9398)
			(stroke
				(width 0)
				(type default)
			)
			(fill no)
			(layer "F.CrtYd")
		)
		(fp_rect
			(start -0.508 0.9398)
			(end 0.508 -0.9398)
			(stroke
				(width 0)
				(type default)
			)
			(fill no)
			(layer "F.Fab")
		)
		(pad "1" smd custom
			(at 0 -0.4445)
			(size 0.1397 0.1397)
			(layers "F.Cu" "F.Mask" "F.Paste")
			(net "P3V3")
			(options
				(clearance outline)
				(anchor circle)
			)
			(primitives
				(gr_poly
					(pts
						(arc
							(start -0.1778 -0.2794)
							(mid -0.249642 -0.249642)
							(end -0.2794 -0.1778)
						)
						(arc
							(start -0.2794 0.1778)
							(mid -0.249642 0.249642)
							(end -0.1778 0.2794)
						)
						(arc
							(start 0.1778 0.2794)
							(mid 0.249642 0.249642)
							(end 0.2794 0.1778)
						)
						(arc
							(start 0.2794 -0.1778)
							(mid 0.249642 -0.249642)
							(end 0.1778 -0.2794)
						)
					)
					(width 0)
					(fill yes)
				)
			)
		)
		(pad "2" smd custom
			(at 0 0.4445)
			(size 0.1397 0.1397)
			(layers "F.Cu" "F.Mask" "F.Paste")
			(net "I2C_C_BUF_SDAOUT")
			(options
				(clearance outline)
				(anchor circle)
			)
			(primitives
				(gr_poly
					(pts
						(arc
							(start -0.1778 -0.2794)
							(mid -0.249642 -0.249642)
							(end -0.2794 -0.1778)
						)
						(arc
							(start -0.2794 0.1778)
							(mid -0.249642 0.249642)
							(end -0.1778 0.2794)
						)
						(arc
							(start 0.1778 0.2794)
							(mid 0.249642 0.249642)
							(end 0.2794 0.1778)
						)
						(arc
							(start 0.2794 -0.1778)
							(mid 0.249642 -0.249642)
							(end 0.1778 -0.2794)
						)
					)
					(width 0)
					(fill yes)
				)
			)
		)
	)
	(footprint ""
		(layer "F.Cu")
		(at 135.086344 -83.972908 90)
		(property "Reference" "R365"
			(at 0 0 90)
			(layer "F.SilkS")
			(hide yes)
			(effects
				(font
					(size 1.27 1.27)
				)
			)
		)
		(property "Value" "0R2J-2-GP"
			(at 0.064008 -3.993896 90)
			(unlocked yes)
			(layer "F.Fab")
			(hide yes)
			(effects
				(font
					(size 1.016 1.016)
					(thickness 0.1524)
				)
			)
		)
		(property "Device Type" "R402H16"
			(at 0.064008 -5.517896 90)
			(unlocked yes)
			(layer "F.Fab")
			(hide yes)
			(effects
				(font
					(size 1.016 1.016)
					(thickness 0.1524)
				)
			)
		)
		(duplicate_pad_numbers_are_jumpers no)
		(fp_line
			(start 0.508 -0.9398)
			(end -0.508 -0.9398)
			(stroke
				(width 0.1524)
				(type default)
			)
			(layer "F.SilkS")
		)
		(fp_line
			(start -0.508 -0.9398)
			(end -0.508 0.9398)
			(stroke
				(width 0.1524)
				(type default)
			)
			(layer "F.SilkS")
		)
		(fp_rect
			(start -0.508 0.9398)
			(end 0.508 -0.9398)
			(stroke
				(width 0)
				(type default)
			)
			(fill no)
			(layer "F.CrtYd")
		)
		(fp_rect
			(start -0.508 0.9398)
			(end 0.508 -0.9398)
			(stroke
				(width 0)
				(type default)
			)
			(fill no)
			(layer "F.Fab")
		)
		(pad "1" smd custom
			(at 0 -0.4445 90)
			(size 0.1397 0.1397)
			(layers "F.Cu" "F.Mask" "F.Paste")
			(net "TRAY PRESENT_OUT_NET")
			(options
				(clearance outline)
				(anchor circle)
			)
			(primitives
				(gr_poly
					(pts
						(arc
							(start -0.1778 -0.2794)
							(mid -0.249642 -0.249642)
							(end -0.2794 -0.1778)
						)
						(arc
							(start -0.2794 0.1778)
							(mid -0.249642 0.249642)
							(end -0.1778 0.2794)
						)
						(arc
							(start 0.1778 0.2794)
							(mid 0.249642 0.249642)
							(end 0.2794 0.1778)
						)
						(arc
							(start 0.2794 -0.1778)
							(mid 0.249642 -0.249642)
							(end 0.1778 -0.2794)
						)
					)
					(width 0)
					(fill yes)
				)
			)
		)
		(pad "2" smd custom
			(at 0 0.4445 90)
			(size 0.1397 0.1397)
			(layers "F.Cu" "F.Mask" "F.Paste")
			(net "TRAY_MOSFET_G")
			(options
				(clearance outline)
				(anchor circle)
			)
			(primitives
				(gr_poly
					(pts
						(arc
							(start -0.1778 -0.2794)
							(mid -0.249642 -0.249642)
							(end -0.2794 -0.1778)
						)
						(arc
							(start -0.2794 0.1778)
							(mid -0.249642 0.249642)
							(end -0.1778 0.2794)
						)
						(arc
							(start 0.1778 0.2794)
							(mid 0.249642 0.249642)
							(end 0.2794 0.1778)
						)
						(arc
							(start 0.2794 -0.1778)
							(mid 0.249642 -0.249642)
							(end 0.1778 -0.2794)
						)
					)
					(width 0)
					(fill yes)
				)
			)
		)
	)
	(footprint ""
		(layer "F.Cu")
		(at 136.152382 -68.318634 90)
		(property "Reference" "R386"
			(at 0 0 90)
			(layer "F.SilkS")
			(hide yes)
			(effects
				(font
					(size 1.27 1.27)
				)
			)
		)
		(property "Value" "0R2J-2-GP"
			(at 0.064008 -3.993896 90)
			(unlocked yes)
			(layer "F.Fab")
			(hide yes)
			(effects
				(font
					(size 1.016 1.016)
					(thickness 0.1524)
				)
			)
		)
		(property "Device Type" "R402H16"
			(at 0.064008 -5.517896 90)
			(unlocked yes)
			(layer "F.Fab")
			(hide yes)
			(effects
				(font
					(size 1.016 1.016)
					(thickness 0.1524)
				)
			)
		)
		(duplicate_pad_numbers_are_jumpers no)
		(fp_line
			(start 0.508 -0.9398)
			(end -0.508 -0.9398)
			(stroke
				(width 0.1524)
				(type default)
			)
			(layer "F.SilkS")
		)
		(fp_line
			(start -0.508 -0.9398)
			(end -0.508 0.9398)
			(stroke
				(width 0.1524)
				(type default)
			)
			(layer "F.SilkS")
		)
		(fp_rect
			(start -0.508 0.9398)
			(end 0.508 -0.9398)
			(stroke
				(width 0)
				(type default)
			)
			(fill no)
			(layer "F.CrtYd")
		)
		(fp_rect
			(start -0.508 0.9398)
			(end 0.508 -0.9398)
			(stroke
				(width 0)
				(type default)
			)
			(fill no)
			(layer "F.Fab")
		)
		(pad "1" smd custom
			(at 0 -0.4445 90)
			(size 0.1397 0.1397)
			(layers "F.Cu" "F.Mask" "F.Paste")
			(net "I2C_C_BUF_SDA")
			(options
				(clearance outline)
				(anchor circle)
			)
			(primitives
				(gr_poly
					(pts
						(arc
							(start -0.1778 -0.2794)
							(mid -0.249642 -0.249642)
							(end -0.2794 -0.1778)
						)
						(arc
							(start -0.2794 0.1778)
							(mid -0.249642 0.249642)
							(end -0.1778 0.2794)
						)
						(arc
							(start 0.1778 0.2794)
							(mid 0.249642 0.249642)
							(end 0.2794 0.1778)
						)
						(arc
							(start 0.2794 -0.1778)
							(mid 0.249642 -0.249642)
							(end 0.1778 -0.2794)
						)
					)
					(width 0)
					(fill yes)
				)
			)
		)
		(pad "2" smd custom
			(at 0 0.4445 90)
			(size 0.1397 0.1397)
			(layers "F.Cu" "F.Mask" "F.Paste")
			(net "I2C_C_BUF_SDA_CONN")
			(options
				(clearance outline)
				(anchor circle)
			)
			(primitives
				(gr_poly
					(pts
						(arc
							(start -0.1778 -0.2794)
							(mid -0.249642 -0.249642)
							(end -0.2794 -0.1778)
						)
						(arc
							(start -0.2794 0.1778)
							(mid -0.249642 0.249642)
							(end -0.1778 0.2794)
						)
						(arc
							(start 0.1778 0.2794)
							(mid 0.249642 0.249642)
							(end 0.2794 0.1778)
						)
						(arc
							(start 0.2794 -0.1778)
							(mid 0.249642 -0.249642)
							(end 0.1778 -0.2794)
						)
					)
					(width 0)
					(fill yes)
				)
			)
		)
	)
	(footprint ""
		(layer "F.Cu")
		(at 152.580086 -56.999886 90)
		(property "Reference" "CN4"
			(at 0 0 90)
			(layer "F.SilkS")
			(hide yes)
			(effects
				(font
					(size 1.27 1.27)
				)
			)
		)
		(property "Value" "FCI-CONN52-4R-GP"
			(at -28.321 -4.0132 90)
			(unlocked yes)
			(layer "F.Fab")
			(hide yes)
			(effects
				(font
					(size 1.016 1.016)
					(thickness 0.1524)
				)
			)
		)
		(property "Device Type" "51939-689LF"
			(at -28.321 -5.5372 90)
			(unlocked yes)
			(layer "F.Fab")
			(hide yes)
			(effects
				(font
					(size 1.016 1.016)
					(thickness 0.1524)
				)
			)
		)
		(duplicate_pad_numbers_are_jumpers no)
		(fp_line
			(start 26.289 -8.6106)
			(end 26.289 5.08)
			(stroke
				(width 0.1524)
				(type default)
			)
			(layer "F.SilkS")
		)
		(fp_line
			(start -26.289 -8.6106)
			(end 26.289 -8.6106)
			(stroke
				(width 0.1524)
				(type default)
			)
			(layer "F.SilkS")
		)
		(fp_line
			(start 26.289 5.08)
			(end -26.289 5.08)
			(stroke
				(width 0.1524)
				(type default)
			)
			(layer "F.SilkS")
		)
		(fp_line
			(start -26.289 5.08)
			(end -26.289 -8.6106)
			(stroke
				(width 0.1524)
				(type default)
			)
			(layer "F.SilkS")
		)
		(fp_circle
			(center 15.88008 -7.62)
			(end 15.88008 -6.5405)
			(stroke
				(width 0.3048)
				(type default)
			)
			(fill no)
			(layer "F.SilkS")
		)
		(fp_circle
			(center 13.34008 -7.62)
			(end 13.34008 -6.5405)
			(stroke
				(width 0.3048)
				(type default)
			)
			(fill no)
			(layer "F.SilkS")
		)
		(fp_circle
			(center 10.80008 -7.62)
			(end 10.80008 -6.5405)
			(stroke
				(width 0.3048)
				(type default)
			)
			(fill no)
			(layer "F.SilkS")
		)
		(fp_circle
			(center 8.26008 -7.62)
			(end 8.26008 -6.5405)
			(stroke
				(width 0.3048)
				(type default)
			)
			(fill no)
			(layer "F.SilkS")
		)
		(fp_circle
			(center 5.08 -7.62)
			(end 5.08 -6.5405)
			(stroke
				(width 0.3048)
				(type default)
			)
			(fill no)
			(layer "F.SilkS")
		)
		(fp_circle
			(center 2.54 -7.62)
			(end 2.54 -6.5405)
			(stroke
				(width 0.3048)
				(type default)
			)
			(fill no)
			(layer "F.SilkS")
		)
		(fp_circle
			(center 0 -7.62)
			(end 0 -6.5405)
			(stroke
				(width 0.3048)
				(type default)
			)
			(fill no)
			(layer "F.SilkS")
		)
		(fp_circle
			(center -2.54 -7.62)
			(end -2.54 -6.5405)
			(stroke
				(width 0.3048)
				(type default)
			)
			(fill no)
			(layer "F.SilkS")
		)
		(fp_circle
			(center -5.08 -7.62)
			(end -5.08 -6.5405)
			(stroke
				(width 0.3048)
				(type default)
			)
			(fill no)
			(layer "F.SilkS")
		)
		(fp_circle
			(center -8.26008 -7.62)
			(end -8.26008 -6.5405)
			(stroke
				(width 0.3048)
				(type default)
			)
			(fill no)
			(layer "F.SilkS")
		)
		(fp_circle
			(center -10.80008 -7.62)
			(end -10.80008 -6.5405)
			(stroke
				(width 0.3048)
				(type default)
			)
			(fill no)
			(layer "F.SilkS")
		)
		(fp_circle
			(center -13.34008 -7.62)
			(end -13.34008 -6.5405)
			(stroke
				(width 0.3048)
				(type default)
			)
			(fill no)
			(layer "F.SilkS")
		)
		(fp_circle
			(center -15.88008 -7.62)
			(end -15.88008 -6.5405)
			(stroke
				(width 0.3048)
				(type default)
			)
			(fill no)
			(layer "F.SilkS")
		)
		(fp_circle
			(center 15.88008 -5.08)
			(end 15.88008 -4.0005)
			(stroke
				(width 0.3048)
				(type default)
			)
			(fill no)
			(layer "F.SilkS")
		)
		(fp_circle
			(center 13.34008 -5.08)
			(end 13.34008 -4.0005)
			(stroke
				(width 0.3048)
				(type default)
			)
			(fill no)
			(layer "F.SilkS")
		)
		(fp_circle
			(center 10.80008 -5.08)
			(end 10.80008 -4.0005)
			(stroke
				(width 0.3048)
				(type default)
			)
			(fill no)
			(layer "F.SilkS")
		)
		(fp_circle
			(center 8.26008 -5.08)
			(end 8.26008 -4.0005)
			(stroke
				(width 0.3048)
				(type default)
			)
			(fill no)
			(layer "F.SilkS")
		)
		(fp_circle
			(center 5.08 -5.08)
			(end 5.08 -4.0005)
			(stroke
				(width 0.3048)
				(type default)
			)
			(fill no)
			(layer "F.SilkS")
		)
		(fp_circle
			(center 2.54 -5.08)
			(end 2.54 -4.0005)
			(stroke
				(width 0.3048)
				(type default)
			)
			(fill no)
			(layer "F.SilkS")
		)
		(fp_circle
			(center 0 -5.08)
			(end 0 -4.0005)
			(stroke
				(width 0.3048)
				(type default)
			)
			(fill no)
			(layer "F.SilkS")
		)
		(fp_circle
			(center -2.54 -5.08)
			(end -2.54 -4.0005)
			(stroke
				(width 0.3048)
				(type default)
			)
			(fill no)
			(layer "F.SilkS")
		)
		(fp_circle
			(center -5.08 -5.08)
			(end -5.08 -4.0005)
			(stroke
				(width 0.3048)
				(type default)
			)
			(fill no)
			(layer "F.SilkS")
		)
		(fp_circle
			(center -8.26008 -5.08)
			(end -8.26008 -4.0005)
			(stroke
				(width 0.3048)
				(type default)
			)
			(fill no)
			(layer "F.SilkS")
		)
		(fp_circle
			(center -10.80008 -5.08)
			(end -10.80008 -4.0005)
			(stroke
				(width 0.3048)
				(type default)
			)
			(fill no)
			(layer "F.SilkS")
		)
		(fp_circle
			(center -13.34008 -5.08)
			(end -13.34008 -4.0005)
			(stroke
				(width 0.3048)
				(type default)
			)
			(fill no)
			(layer "F.SilkS")
		)
		(fp_circle
			(center -15.88008 -5.08)
			(end -15.88008 -4.0005)
			(stroke
				(width 0.3048)
				(type default)
			)
			(fill no)
			(layer "F.SilkS")
		)
		(fp_circle
			(center 15.88008 -2.54)
			(end 15.88008 -1.4605)
			(stroke
				(width 0.3048)
				(type default)
			)
			(fill no)
			(layer "F.SilkS")
		)
		(fp_circle
			(center 13.34008 -2.54)
			(end 13.34008 -1.4605)
			(stroke
				(width 0.3048)
				(type default)
			)
			(fill no)
			(layer "F.SilkS")
		)
		(fp_circle
			(center 10.80008 -2.54)
			(end 10.80008 -1.4605)
			(stroke
				(width 0.3048)
				(type default)
			)
			(fill no)
			(layer "F.SilkS")
		)
		(fp_circle
			(center 8.26008 -2.54)
			(end 8.26008 -1.4605)
			(stroke
				(width 0.3048)
				(type default)
			)
			(fill no)
			(layer "F.SilkS")
		)
		(fp_circle
			(center 5.08 -2.54)
			(end 5.08 -1.4605)
			(stroke
				(width 0.3048)
				(type default)
			)
			(fill no)
			(layer "F.SilkS")
		)
		(fp_circle
			(center 2.54 -2.54)
			(end 2.54 -1.4605)
			(stroke
				(width 0.3048)
				(type default)
			)
			(fill no)
			(layer "F.SilkS")
		)
		(fp_circle
			(center 0 -2.54)
			(end 0 -1.4605)
			(stroke
				(width 0.3048)
				(type default)
			)
			(fill no)
			(layer "F.SilkS")
		)
		(fp_circle
			(center -2.54 -2.54)
			(end -2.54 -1.4605)
			(stroke
				(width 0.3048)
				(type default)
			)
			(fill no)
			(layer "F.SilkS")
		)
		(fp_circle
			(center -5.08 -2.54)
			(end -5.08 -1.4605)
			(stroke
				(width 0.3048)
				(type default)
			)
			(fill no)
			(layer "F.SilkS")
		)
		(fp_circle
			(center -8.26008 -2.54)
			(end -8.26008 -1.4605)
			(stroke
				(width 0.3048)
				(type default)
			)
			(fill no)
			(layer "F.SilkS")
		)
		(fp_circle
			(center -10.80008 -2.54)
			(end -10.80008 -1.4605)
			(stroke
				(width 0.3048)
				(type default)
			)
			(fill no)
			(layer "F.SilkS")
		)
		(fp_circle
			(center -13.34008 -2.54)
			(end -13.34008 -1.4605)
			(stroke
				(width 0.3048)
				(type default)
			)
			(fill no)
			(layer "F.SilkS")
		)
		(fp_circle
			(center -15.88008 -2.54)
			(end -15.88008 -1.4605)
			(stroke
				(width 0.3048)
				(type default)
			)
			(fill no)
			(layer "F.SilkS")
		)
		(fp_circle
			(center 15.88008 0)
			(end 15.88008 1.0795)
			(stroke
				(width 0.3048)
				(type default)
			)
			(fill no)
			(layer "F.SilkS")
		)
		(fp_circle
			(center 13.34008 0)
			(end 13.34008 1.0795)
			(stroke
				(width 0.3048)
				(type default)
			)
			(fill no)
			(layer "F.SilkS")
		)
		(fp_circle
			(center 10.80008 0)
			(end 10.80008 1.0795)
			(stroke
				(width 0.3048)
				(type default)
			)
			(fill no)
			(layer "F.SilkS")
		)
		(fp_circle
			(center 8.26008 0)
			(end 8.26008 1.0795)
			(stroke
				(width 0.3048)
				(type default)
			)
			(fill no)
			(layer "F.SilkS")
		)
		(fp_circle
			(center 5.08 0)
			(end 5.08 1.0795)
			(stroke
				(width 0.3048)
				(type default)
			)
			(fill no)
			(layer "F.SilkS")
		)
		(fp_circle
			(center 2.54 0)
			(end 2.54 1.0795)
			(stroke
				(width 0.3048)
				(type default)
			)
			(fill no)
			(layer "F.SilkS")
		)
		(fp_circle
			(center 0 0)
			(end 0 1.0795)
			(stroke
				(width 0.3048)
				(type default)
			)
			(fill no)
			(layer "F.SilkS")
		)
		(fp_circle
			(center -2.54 0)
			(end -2.54 1.0795)
			(stroke
				(width 0.3048)
				(type default)
			)
			(fill no)
			(layer "F.SilkS")
		)
		(fp_circle
			(center -5.08 0)
			(end -5.08 1.0795)
			(stroke
				(width 0.3048)
				(type default)
			)
			(fill no)
			(layer "F.SilkS")
		)
		(fp_circle
			(center -8.26008 0)
			(end -8.26008 1.0795)
			(stroke
				(width 0.3048)
				(type default)
			)
			(fill no)
			(layer "F.SilkS")
		)
		(fp_circle
			(center -10.80008 0)
			(end -10.80008 1.0795)
			(stroke
				(width 0.3048)
				(type default)
			)
			(fill no)
			(layer "F.SilkS")
		)
		(fp_circle
			(center -13.34008 0)
			(end -13.34008 1.0795)
			(stroke
				(width 0.3048)
				(type default)
			)
			(fill no)
			(layer "F.SilkS")
		)
		(fp_circle
			(center -15.88008 0)
			(end -15.88008 1.0795)
			(stroke
				(width 0.3048)
				(type default)
			)
			(fill no)
			(layer "F.SilkS")
		)
		(fp_rect
			(start -26.035 15.367)
			(end 26.035 -8.255)
			(stroke
				(width 0)
				(type default)
			)
			(fill no)
			(layer "F.CrtYd")
		)
		(fp_poly
			(pts
				(xy -26.543 15.875) (xy -26.543 -11.684) (xy 26.543 -11.684) (xy 26.543 -0.00635) (xy 26.035 -0.00635)
				(xy 26.035 -8.255) (xy -26.035 -8.255) (xy -26.035 15.367) (xy 26.035 15.367) (xy 26.035 0.00635)
				(xy 26.543 0.00635) (xy 26.543 15.875)
			)
			(stroke
				(width 0)
				(type default)
			)
			(fill no)
			(layer "F.CrtYd")
		)
		(fp_rect
			(start -26.543 15.875)
			(end 26.543 -11.684)
			(stroke
				(width 0)
				(type default)
			)
			(fill no)
			(layer "F.Fab")
		)
		(fp_text user "Slit"
			(at -1.7399 8.0645 90)
			(unlocked yes)
			(layer "F.SilkS")
			(effects
				(font
					(size 1.016 1.016)
					(thickness 0.1524)
				)
				(justify left)
			)
		)
		(pad "" np_thru_hole circle
			(at -22.225 0 90)
			(size 0.254 0.254)
			(drill 4.0132)
			(layers "*.Cu" "*.Mask")
			(clearance 2.2352)
			(thermal_gap 2.2352)
		)
		(pad "" np_thru_hole circle
			(at 22.225 0 90)
			(size 0.254 0.254)
			(drill 4.0132)
			(layers "*.Cu" "*.Mask")
			(clearance 2.2352)
			(thermal_gap 2.2352)
		)
		(pad "A1" thru_hole circle
			(at -5.08 0 90)
			(size 1.4478 1.4478)
			(drill 1.0414)
			(layers "*.Cu" "*.Mask")
			(remove_unused_layers no)
			(net "I2C_C_BUF_SDA_CONN")
			(clearance 0.1524)
			(thermal_gap 0.1524)
		)
		(pad "A2" thru_hole circle
			(at -2.54 0 90)
			(size 1.4478 1.4478)
			(drill 1.0414)
			(layers "*.Cu" "*.Mask")
			(remove_unused_layers no)
			(net "GND")
			(clearance 0.1524)
			(thermal_gap 0.1524)
		)
		(pad "A3" thru_hole circle
			(at 0 0 90)
			(size 1.4478 1.4478)
			(drill 1.0414)
			(layers "*.Cu" "*.Mask")
			(remove_unused_layers no)
			(net "I2C_C_BUF_SCL_CONN")
			(clearance 0.1524)
			(thermal_gap 0.1524)
		)
		(pad "A4" thru_hole circle
			(at 2.54 0 90)
			(size 1.4478 1.4478)
			(drill 1.0414)
			(layers "*.Cu" "*.Mask")
			(remove_unused_layers no)
			(net "GND")
			(clearance 0.1524)
			(thermal_gap 0.1524)
		)
		(pad "A5" thru_hole circle
			(at 5.08 0 90)
			(size 1.4478 1.4478)
			(drill 1.0414)
			(layers "*.Cu" "*.Mask")
			(remove_unused_layers no)
			(net "PWM_EXP_B_OUT")
			(clearance 0.1524)
			(thermal_gap 0.1524)
		)
		(pad "B1" thru_hole circle
			(at -5.08 -2.54 90)
			(size 1.4478 1.4478)
			(drill 1.0414)
			(layers "*.Cu" "*.Mask")
			(remove_unused_layers no)
			(net "GND")
			(clearance 0.1524)
			(thermal_gap 0.1524)
		)
		(pad "B2" thru_hole circle
			(at -2.54 -2.54 90)
			(size 1.4478 1.4478)
			(drill 1.0414)
			(layers "*.Cu" "*.Mask")
			(remove_unused_layers no)
			(net "PWM_EXP_A_OUT")
			(clearance 0.1524)
			(thermal_gap 0.1524)
		)
		(pad "B3" thru_hole circle
			(at 0 -2.54 90)
			(size 1.4478 1.4478)
			(drill 1.0414)
			(layers "*.Cu" "*.Mask")
			(remove_unused_layers no)
			(net "GND")
			(clearance 0.1524)
			(thermal_gap 0.1524)
		)
		(pad "B4" thru_hole circle
			(at 2.54 -2.54 90)
			(size 1.4478 1.4478)
			(drill 1.0414)
			(layers "*.Cu" "*.Mask")
			(remove_unused_layers no)
			(net "SELF_1B&2B_HB")
			(clearance 0.1524)
			(thermal_gap 0.1524)
		)
		(pad "B5" thru_hole circle
			(at 5.08 -2.54 90)
			(size 1.4478 1.4478)
			(drill 1.0414)
			(layers "*.Cu" "*.Mask")
			(remove_unused_layers no)
			(net "GND")
			(clearance 0.1524)
			(thermal_gap 0.1524)
		)
		(pad "C1" thru_hole circle
			(at -5.08 -5.08 90)
			(size 1.4478 1.4478)
			(drill 1.0414)
			(layers "*.Cu" "*.Mask")
			(remove_unused_layers no)
			(net "TPS2490_EN1")
			(clearance 0.1524)
			(thermal_gap 0.1524)
		)
		(pad "C2" thru_hole circle
			(at -2.54 -5.08 90)
			(size 1.4478 1.4478)
			(drill 1.0414)
			(layers "*.Cu" "*.Mask")
			(remove_unused_layers no)
			(net "TPS2490_EN2")
			(clearance 0.1524)
			(thermal_gap 0.1524)
		)
		(pad "C3" thru_hole circle
			(at 0 -5.08 90)
			(size 1.4478 1.4478)
			(drill 1.0414)
			(layers "*.Cu" "*.Mask")
			(remove_unused_layers no)
			(net "SELF_1A&2A_HB")
			(clearance 0.1524)
			(thermal_gap 0.1524)
		)
		(pad "C4" thru_hole circle
			(at 2.54 -5.08 90)
			(size 1.4478 1.4478)
			(drill 1.0414)
			(layers "*.Cu" "*.Mask")
			(remove_unused_layers no)
			(net "PEER_1A&2A_HB")
			(clearance 0.1524)
			(thermal_gap 0.1524)
		)
		(pad "C5" thru_hole circle
			(at 5.08 -5.08 90)
			(size 1.4478 1.4478)
			(drill 1.0414)
			(layers "*.Cu" "*.Mask")
			(remove_unused_layers no)
			(net "PEER_1B&2B_HB")
			(clearance 0.1524)
			(thermal_gap 0.1524)
		)
		(pad "D1" thru_hole circle
			(at -5.08 -7.62 90)
			(size 1.4478 1.4478)
			(drill 1.0414)
			(layers "*.Cu" "*.Mask")
			(remove_unused_layers no)
			(net "PEER_TRAY_PRESENT")
			(clearance 0.1524)
			(thermal_gap 0.1524)
		)
		(pad "D2" thru_hole circle
			(at -2.54 -7.62 90)
			(size 1.4478 1.4478)
			(drill 1.0414)
			(layers "*.Cu" "*.Mask")
			(remove_unused_layers no)
			(net "TRAY_ID")
			(clearance 0.1524)
			(thermal_gap 0.1524)
		)
		(pad "D3" thru_hole circle
			(at 0 -7.62 90)
			(size 1.4478 1.4478)
			(drill 1.0414)
			(layers "*.Cu" "*.Mask")
			(remove_unused_layers no)
			(net "FCB_HW_REV")
			(clearance 0.1524)
			(thermal_gap 0.1524)
		)
		(pad "D4" thru_hole circle
			(at 2.54 -7.62 90)
			(size 1.4478 1.4478)
			(drill 1.0414)
			(layers "*.Cu" "*.Mask")
			(remove_unused_layers no)
			(net "SD_LATCH_RELEASE")
			(clearance 0.1524)
			(thermal_gap 0.1524)
		)
		(pad "D5" thru_hole circle
			(at 5.08 -7.62 90)
			(size 1.4478 1.4478)
			(drill 1.0414)
			(layers "*.Cu" "*.Mask")
			(remove_unused_layers no)
			(net "SELF_TRAY_PRESENT")
			(clearance 0.1524)
			(thermal_gap 0.1524)
		)
		(pad "P1_1" thru_hole circle
			(at -15.88008 0 90)
			(size 1.4478 1.4478)
			(drill 1.0414)
			(layers "*.Cu" "*.Mask")
			(remove_unused_layers no)
			(net "P12V")
			(clearance 0.1524)
			(thermal_gap 0.1524)
		)
		(pad "P1_2" thru_hole circle
			(at -15.88008 -2.54 90)
			(size 1.4478 1.4478)
			(drill 1.0414)
			(layers "*.Cu" "*.Mask")
			(remove_unused_layers no)
			(net "P12V")
			(clearance 0.1524)
			(thermal_gap 0.1524)
		)
		(pad "P1_3" thru_hole circle
			(at -15.88008 -5.08 90)
			(size 1.4478 1.4478)
			(drill 1.0414)
			(layers "*.Cu" "*.Mask")
			(remove_unused_layers no)
			(net "P12V")
			(clearance 0.1524)
			(thermal_gap 0.1524)
		)
		(pad "P1_4" thru_hole circle
			(at -15.88008 -7.62 90)
			(size 1.4478 1.4478)
			(drill 1.0414)
			(layers "*.Cu" "*.Mask")
			(remove_unused_layers no)
			(net "P12V")
			(clearance 0.1524)
			(thermal_gap 0.1524)
		)
		(pad "P1_5" thru_hole circle
			(at -13.34008 0 90)
			(size 1.4478 1.4478)
			(drill 1.0414)
			(layers "*.Cu" "*.Mask")
			(remove_unused_layers no)
			(net "P12V")
			(clearance 0.1524)
			(thermal_gap 0.1524)
		)
		(pad "P1_6" thru_hole circle
			(at -13.34008 -2.54 90)
			(size 1.4478 1.4478)
			(drill 1.0414)
			(layers "*.Cu" "*.Mask")
			(remove_unused_layers no)
			(net "P12V")
			(clearance 0.1524)
			(thermal_gap 0.1524)
		)
		(pad "P1_7" thru_hole circle
			(at -13.34008 -5.08 90)
			(size 1.4478 1.4478)
			(drill 1.0414)
			(layers "*.Cu" "*.Mask")
			(remove_unused_layers no)
			(net "P12V")
			(clearance 0.1524)
			(thermal_gap 0.1524)
		)
		(pad "P1_8" thru_hole circle
			(at -13.34008 -7.62 90)
			(size 1.4478 1.4478)
			(drill 1.0414)
			(layers "*.Cu" "*.Mask")
			(remove_unused_layers no)
			(net "P12V")
			(clearance 0.1524)
			(thermal_gap 0.1524)
		)
		(pad "P2_1" thru_hole circle
			(at -10.80008 0 90)
			(size 1.4478 1.4478)
			(drill 1.0414)
			(layers "*.Cu" "*.Mask")
			(remove_unused_layers no)
			(net "P12V")
			(clearance 0.1524)
			(thermal_gap 0.1524)
		)
		(pad "P2_2" thru_hole circle
			(at -10.80008 -2.54 90)
			(size 1.4478 1.4478)
			(drill 1.0414)
			(layers "*.Cu" "*.Mask")
			(remove_unused_layers no)
			(net "P12V")
			(clearance 0.1524)
			(thermal_gap 0.1524)
		)
		(pad "P2_3" thru_hole circle
			(at -10.80008 -5.08 90)
			(size 1.4478 1.4478)
			(drill 1.0414)
			(layers "*.Cu" "*.Mask")
			(remove_unused_layers no)
			(net "P12V")
			(clearance 0.1524)
			(thermal_gap 0.1524)
		)
		(pad "P2_4" thru_hole circle
			(at -10.80008 -7.62 90)
			(size 1.4478 1.4478)
			(drill 1.0414)
			(layers "*.Cu" "*.Mask")
			(remove_unused_layers no)
			(net "P12V")
			(clearance 0.1524)
			(thermal_gap 0.1524)
		)
		(pad "P2_5" thru_hole circle
			(at -8.26008 0 90)
			(size 1.4478 1.4478)
			(drill 1.0414)
			(layers "*.Cu" "*.Mask")
			(remove_unused_layers no)
			(net "P12V")
			(clearance 0.1524)
			(thermal_gap 0.1524)
		)
		(pad "P2_6" thru_hole circle
			(at -8.26008 -2.54 90)
			(size 1.4478 1.4478)
			(drill 1.0414)
			(layers "*.Cu" "*.Mask")
			(remove_unused_layers no)
			(net "P12V")
			(clearance 0.1524)
			(thermal_gap 0.1524)
		)
		(pad "P2_7" thru_hole circle
			(at -8.26008 -5.08 90)
			(size 1.4478 1.4478)
			(drill 1.0414)
			(layers "*.Cu" "*.Mask")
			(remove_unused_layers no)
			(net "P12V")
			(clearance 0.1524)
			(thermal_gap 0.1524)
		)
		(pad "P2_8" thru_hole circle
			(at -8.26008 -7.62 90)
			(size 1.4478 1.4478)
			(drill 1.0414)
			(layers "*.Cu" "*.Mask")
			(remove_unused_layers no)
			(net "P12V")
			(clearance 0.1524)
			(thermal_gap 0.1524)
		)
		(pad "P3_1" thru_hole circle
			(at 8.26008 0 90)
			(size 1.4478 1.4478)
			(drill 1.0414)
			(layers "*.Cu" "*.Mask")
			(remove_unused_layers no)
			(net "GND")
			(clearance 0.1524)
			(thermal_gap 0.1524)
		)
		(pad "P3_2" thru_hole circle
			(at 8.26008 -2.54 90)
			(size 1.4478 1.4478)
			(drill 1.0414)
			(layers "*.Cu" "*.Mask")
			(remove_unused_layers no)
			(net "GND")
			(clearance 0.1524)
			(thermal_gap 0.1524)
		)
		(pad "P3_3" thru_hole circle
			(at 8.26008 -5.08 90)
			(size 1.4478 1.4478)
			(drill 1.0414)
			(layers "*.Cu" "*.Mask")
			(remove_unused_layers no)
			(net "GND")
			(clearance 0.1524)
			(thermal_gap 0.1524)
		)
		(pad "P3_4" thru_hole circle
			(at 8.26008 -7.62 90)
			(size 1.4478 1.4478)
			(drill 1.0414)
			(layers "*.Cu" "*.Mask")
			(remove_unused_layers no)
			(net "GND")
			(clearance 0.1524)
			(thermal_gap 0.1524)
		)
		(pad "P3_5" thru_hole circle
			(at 10.80008 0 90)
			(size 1.4478 1.4478)
			(drill 1.0414)
			(layers "*.Cu" "*.Mask")
			(remove_unused_layers no)
			(net "GND")
			(clearance 0.1524)
			(thermal_gap 0.1524)
		)
		(pad "P3_6" thru_hole circle
			(at 10.80008 -2.54 90)
			(size 1.4478 1.4478)
			(drill 1.0414)
			(layers "*.Cu" "*.Mask")
			(remove_unused_layers no)
			(net "GND")
			(clearance 0.1524)
			(thermal_gap 0.1524)
		)
		(pad "P3_7" thru_hole circle
			(at 10.80008 -5.08 90)
			(size 1.4478 1.4478)
			(drill 1.0414)
			(layers "*.Cu" "*.Mask")
			(remove_unused_layers no)
			(net "GND")
			(clearance 0.1524)
			(thermal_gap 0.1524)
		)
		(pad "P3_8" thru_hole circle
			(at 10.80008 -7.62 90)
			(size 1.4478 1.4478)
			(drill 1.0414)
			(layers "*.Cu" "*.Mask")
			(remove_unused_layers no)
			(net "GND")
			(clearance 0.1524)
			(thermal_gap 0.1524)
		)
		(pad "P4_1" thru_hole circle
			(at 13.34008 0 90)
			(size 1.4478 1.4478)
			(drill 1.0414)
			(layers "*.Cu" "*.Mask")
			(remove_unused_layers no)
			(net "GND")
			(clearance 0.1524)
			(thermal_gap 0.1524)
		)
		(pad "P4_2" thru_hole circle
			(at 13.34008 -2.54 90)
			(size 1.4478 1.4478)
			(drill 1.0414)
			(layers "*.Cu" "*.Mask")
			(remove_unused_layers no)
			(net "GND")
			(clearance 0.1524)
			(thermal_gap 0.1524)
		)
		(pad "P4_3" thru_hole circle
			(at 13.34008 -5.08 90)
			(size 1.4478 1.4478)
			(drill 1.0414)
			(layers "*.Cu" "*.Mask")
			(remove_unused_layers no)
			(net "GND")
			(clearance 0.1524)
			(thermal_gap 0.1524)
		)
		(pad "P4_4" thru_hole circle
			(at 13.34008 -7.62 90)
			(size 1.4478 1.4478)
			(drill 1.0414)
			(layers "*.Cu" "*.Mask")
			(remove_unused_layers no)
			(net "GND")
			(clearance 0.1524)
			(thermal_gap 0.1524)
		)
		(pad "P4_5" thru_hole circle
			(at 15.88008 0 90)
			(size 1.4478 1.4478)
			(drill 1.0414)
			(layers "*.Cu" "*.Mask")
			(remove_unused_layers no)
			(net "GND")
			(clearance 0.1524)
			(thermal_gap 0.1524)
		)
		(pad "P4_6" thru_hole circle
			(at 15.88008 -2.54 90)
			(size 1.4478 1.4478)
			(drill 1.0414)
			(layers "*.Cu" "*.Mask")
			(remove_unused_layers no)
			(net "GND")
			(clearance 0.1524)
			(thermal_gap 0.1524)
		)
		(pad "P4_7" thru_hole circle
			(at 15.88008 -5.08 90)
			(size 1.4478 1.4478)
			(drill 1.0414)
			(layers "*.Cu" "*.Mask")
			(remove_unused_layers no)
			(net "GND")
			(clearance 0.1524)
			(thermal_gap 0.1524)
		)
		(pad "P4_8" thru_hole circle
			(at 15.88008 -7.62 90)
			(size 1.4478 1.4478)
			(drill 1.0414)
			(layers "*.Cu" "*.Mask")
			(remove_unused_layers no)
			(net "GND")
			(clearance 0.1524)
			(thermal_gap 0.1524)
		)
		(zone
			(layers "F.Cu" "B.Cu" "In1.Cu" "In2.Cu")
			(hatch none 0.5)
			(connect_pads
				(clearance 0)
			)
			(min_thickness 0.25)
			(keepout
				(tracks not_allowed)
				(vias allowed)
				(pads allowed)
				(copperpour not_allowed)
				(footprints allowed)
			)
			(placement
				(enabled no)
				(sheetname "")
			)
			(fill
				(thermal_gap 0.5)
				(thermal_bridge_width 0.5)
				(island_removal_mode 0)
			)
			(polygon
				(pts
					(arc
						(start 154.891486 -79.224886)
						(mid 150.268686 -79.224886)
						(end 154.891486 -79.224886)
					)
				)
			)
		)
		(zone
			(layers "F.Cu" "B.Cu" "In1.Cu" "In2.Cu")
			(hatch none 0.5)
			(connect_pads
				(clearance 0)
			)
			(min_thickness 0.25)
			(keepout
				(tracks not_allowed)
				(vias allowed)
				(pads allowed)
				(copperpour not_allowed)
				(footprints allowed)
			)
			(placement
				(enabled no)
				(sheetname "")
			)
			(fill
				(thermal_gap 0.5)
				(thermal_bridge_width 0.5)
				(island_removal_mode 0)
			)
			(polygon
				(pts
					(arc
						(start 154.891486 -34.774886)
						(mid 150.268686 -34.774886)
						(end 154.891486 -34.774886)
					)
				)
			)
		)
	)
	(footprint ""
		(layer "F.Cu")
		(at 120.116092 -47.354744 180)
		(property "Reference" "C355"
			(at 0 0 180)
			(layer "F.SilkS")
			(hide yes)
			(effects
				(font
					(size 1.27 1.27)
				)
			)
		)
		(property "Value" "SC10U25V5KX-GP"
			(at -0.0762 -6.1214 180)
			(unlocked yes)
			(layer "F.Fab")
			(hide yes)
			(effects
				(font
					(size 1.016 1.016)
					(thickness 0.1524)
				)
			)
		)
		(property "Device Type" "C805H56"
			(at -0.0762 -8.1534 180)
			(unlocked yes)
			(layer "F.Fab")
			(hide yes)
			(effects
				(font
					(size 1.016 1.016)
					(thickness 0.1524)
				)
			)
		)
		(duplicate_pad_numbers_are_jumpers no)
		(fp_line
			(start 0.635 0)
			(end -0.635 0)
			(stroke
				(width 0.508)
				(type default)
			)
			(layer "F.SilkS")
		)
		(fp_rect
			(start -0.9652 1.778)
			(end 0.9652 -1.778)
			(stroke
				(width 0)
				(type default)
			)
			(fill no)
			(layer "F.CrtYd")
		)
		(fp_poly
			(pts
				(xy -0.9652 -1.778) (xy 0.9652 -1.778) (xy 0.9652 1.778) (xy -0.9652 1.778)
			)
			(stroke
				(width 0)
				(type default)
			)
			(fill no)
			(layer "F.Fab")
		)
		(pad "1" smd rect
			(at 0 -0.9652 180)
			(size 1.397 1.143)
			(layers "F.Cu" "F.Mask" "F.Paste")
			(net "P12V")
		)
		(pad "2" smd rect
			(at 0 0.9652 180)
			(size 1.397 1.143)
			(layers "F.Cu" "F.Mask" "F.Paste")
			(net "GND")
		)
	)
	(footprint ""
		(layer "F.Cu")
		(at 135.086344 -85.065108 -90)
		(property "Reference" "R366"
			(at 0 0 270)
			(layer "F.SilkS")
			(hide yes)
			(effects
				(font
					(size 1.27 1.27)
				)
			)
		)
		(property "Value" "0R2J-2-GP"
			(at 0.064008 -3.993896 270)
			(unlocked yes)
			(layer "F.Fab")
			(hide yes)
			(effects
				(font
					(size 1.016 1.016)
					(thickness 0.1524)
				)
			)
		)
		(property "Device Type" "R402H16"
			(at 0.064008 -5.517896 270)
			(unlocked yes)
			(layer "F.Fab")
			(hide yes)
			(effects
				(font
					(size 1.016 1.016)
					(thickness 0.1524)
				)
			)
		)
		(duplicate_pad_numbers_are_jumpers no)
		(fp_line
			(start -0.508 -0.9398)
			(end -0.508 0.9398)
			(stroke
				(width 0.1524)
				(type default)
			)
			(layer "F.SilkS")
		)
		(fp_line
			(start 0.508 -0.9398)
			(end -0.508 -0.9398)
			(stroke
				(width 0.1524)
				(type default)
			)
			(layer "F.SilkS")
		)
		(fp_rect
			(start -0.508 0.9398)
			(end 0.508 -0.9398)
			(stroke
				(width 0)
				(type default)
			)
			(fill no)
			(layer "F.CrtYd")
		)
		(fp_rect
			(start -0.508 0.9398)
			(end 0.508 -0.9398)
			(stroke
				(width 0)
				(type default)
			)
			(fill no)
			(layer "F.Fab")
		)
		(pad "1" smd custom
			(at 0 -0.4445 270)
			(size 0.1397 0.1397)
			(layers "F.Cu" "F.Mask" "F.Paste")
			(net "IR_SWITCH_E")
			(options
				(clearance outline)
				(anchor circle)
			)
			(primitives
				(gr_poly
					(pts
						(arc
							(start -0.1778 -0.2794)
							(mid -0.249642 -0.249642)
							(end -0.2794 -0.1778)
						)
						(arc
							(start -0.2794 0.1778)
							(mid -0.249642 0.249642)
							(end -0.1778 0.2794)
						)
						(arc
							(start 0.1778 0.2794)
							(mid 0.249642 0.249642)
							(end 0.2794 0.1778)
						)
						(arc
							(start 0.2794 -0.1778)
							(mid 0.249642 -0.249642)
							(end 0.1778 -0.2794)
						)
					)
					(width 0)
					(fill yes)
				)
			)
		)
		(pad "2" smd custom
			(at 0 0.4445 270)
			(size 0.1397 0.1397)
			(layers "F.Cu" "F.Mask" "F.Paste")
			(net "TRAY PRESENT_OUT_NET")
			(options
				(clearance outline)
				(anchor circle)
			)
			(primitives
				(gr_poly
					(pts
						(arc
							(start -0.1778 -0.2794)
							(mid -0.249642 -0.249642)
							(end -0.2794 -0.1778)
						)
						(arc
							(start -0.2794 0.1778)
							(mid -0.249642 0.249642)
							(end -0.1778 0.2794)
						)
						(arc
							(start 0.1778 0.2794)
							(mid 0.249642 0.249642)
							(end 0.2794 0.1778)
						)
						(arc
							(start 0.2794 -0.1778)
							(mid 0.249642 -0.249642)
							(end 0.1778 -0.2794)
						)
					)
					(width 0)
					(fill yes)
				)
			)
		)
	)
	(footprint ""
		(layer "F.Cu")
		(at 7.659878 -15.499842)
		(property "Reference" "H3"
			(at 0 0 0)
			(layer "F.SilkS")
			(hide yes)
			(effects
				(font
					(size 1.27 1.27)
				)
			)
		)
		(property "Value" "HOLE"
			(at -8.9789 -1.1176 0)
			(unlocked yes)
			(layer "F.Fab")
			(hide yes)
			(effects
				(font
					(size 1.016 1.016)
					(thickness 0.1524)
				)
			)
		)
		(property "Device Type" "HTE9B9R355-R-766"
			(at -8.9789 -2.6416 0)
			(unlocked yes)
			(layer "F.Fab")
			(hide yes)
			(effects
				(font
					(size 1.016 1.016)
					(thickness 0.1524)
				)
			)
		)
		(duplicate_pad_numbers_are_jumpers no)
		(fp_poly
			(pts
				(arc
					(start 4.8133 0)
					(mid -4.8133 0)
					(end 4.8133 0)
				)
			)
			(stroke
				(width 0)
				(type default)
			)
			(fill no)
			(layer "B.CrtYd")
		)
		(fp_poly
			(pts
				(arc
					(start 0 -4.8133)
					(mid 4.8133 0)
					(end 0 4.8133)
				)
				(xy -7.9629 4.8133) (xy -7.9629 -4.8133)
			)
			(stroke
				(width 0)
				(type default)
			)
			(fill no)
			(layer "F.CrtYd")
		)
		(fp_poly
			(pts
				(arc
					(start 4.8133 0)
					(mid -4.8133 0)
					(end 4.8133 0)
				)
			)
			(stroke
				(width 0)
				(type default)
			)
			(fill no)
			(layer "B.Fab")
		)
		(fp_poly
			(pts
				(arc
					(start 0 -4.8133)
					(mid 4.8133 0)
					(end 0 4.8133)
				)
				(xy -7.9629 4.8133) (xy -7.9629 -4.8133)
			)
			(stroke
				(width 0)
				(type default)
			)
			(fill no)
			(layer "F.Fab")
		)
		(pad "1" thru_hole custom
			(at 0 0)
			(size 2.25425 2.25425)
			(drill 3.556)
			(layers "*.Cu" "*.Mask")
			(remove_unused_layers no)
			(net "GND")
			(clearance -3.7973)
			(thermal_gap 0.3048)
			(options
				(clearance outline)
				(anchor circle)
			)
			(primitives
				(gr_poly
					(pts
						(arc
							(start 1.5748 -4.5085)
							(mid 6.0833 0)
							(end 1.5748 4.5085)
						)
						(xy -6.0833 4.5085) (xy -6.0833 -4.5085)
					)
					(width 0)
					(fill yes)
				)
			)
			(padstack
				(mode front_inner_back)
				(layer "Inner"
					(shape circle)
					(size 3.9624 3.9624)
					(clearance 0.3048)
				)
				(layer "B.Cu"
					(shape circle)
					(size 9.017 9.017)
					(clearance -2.2225)
				)
			)
		)
	)
	(footprint ""
		(layer "F.Cu")
		(at 133.223 -82.804 90)
		(property "Reference" "R376"
			(at 0 0 90)
			(layer "F.SilkS")
			(hide yes)
			(effects
				(font
					(size 1.27 1.27)
				)
			)
		)
		(property "Value" "100KR2F-L1-GP"
			(at 0.064008 -3.993896 90)
			(unlocked yes)
			(layer "F.Fab")
			(hide yes)
			(effects
				(font
					(size 1.016 1.016)
					(thickness 0.1524)
				)
			)
		)
		(property "Device Type" "R402H16"
			(at 0.064008 -5.517896 90)
			(unlocked yes)
			(layer "F.Fab")
			(hide yes)
			(effects
				(font
					(size 1.016 1.016)
					(thickness 0.1524)
				)
			)
		)
		(duplicate_pad_numbers_are_jumpers no)
		(fp_line
			(start 0.508 -0.9398)
			(end -0.508 -0.9398)
			(stroke
				(width 0.1524)
				(type default)
			)
			(layer "F.SilkS")
		)
		(fp_line
			(start -0.508 -0.9398)
			(end -0.508 0.9398)
			(stroke
				(width 0.1524)
				(type default)
			)
			(layer "F.SilkS")
		)
		(fp_rect
			(start -0.508 0.9398)
			(end 0.508 -0.9398)
			(stroke
				(width 0)
				(type default)
			)
			(fill no)
			(layer "F.CrtYd")
		)
		(fp_rect
			(start -0.508 0.9398)
			(end 0.508 -0.9398)
			(stroke
				(width 0)
				(type default)
			)
			(fill no)
			(layer "F.Fab")
		)
		(pad "1" smd custom
			(at 0 -0.4445 90)
			(size 0.1397 0.1397)
			(layers "F.Cu" "F.Mask" "F.Paste")
			(net "P3V3")
			(options
				(clearance outline)
				(anchor circle)
			)
			(primitives
				(gr_poly
					(pts
						(arc
							(start -0.1778 -0.2794)
							(mid -0.249642 -0.249642)
							(end -0.2794 -0.1778)
						)
						(arc
							(start -0.2794 0.1778)
							(mid -0.249642 0.249642)
							(end -0.1778 0.2794)
						)
						(arc
							(start 0.1778 0.2794)
							(mid 0.249642 0.249642)
							(end 0.2794 0.1778)
						)
						(arc
							(start 0.2794 -0.1778)
							(mid 0.249642 -0.249642)
							(end 0.1778 -0.2794)
						)
					)
					(width 0)
					(fill yes)
				)
			)
		)
		(pad "2" smd custom
			(at 0 0.4445 90)
			(size 0.1397 0.1397)
			(layers "F.Cu" "F.Mask" "F.Paste")
			(net "TRAY PRESENT_OUT#_C")
			(options
				(clearance outline)
				(anchor circle)
			)
			(primitives
				(gr_poly
					(pts
						(arc
							(start -0.1778 -0.2794)
							(mid -0.249642 -0.249642)
							(end -0.2794 -0.1778)
						)
						(arc
							(start -0.2794 0.1778)
							(mid -0.249642 0.249642)
							(end -0.1778 0.2794)
						)
						(arc
							(start 0.1778 0.2794)
							(mid 0.249642 0.249642)
							(end 0.2794 0.1778)
						)
						(arc
							(start 0.2794 -0.1778)
							(mid 0.249642 -0.249642)
							(end 0.1778 -0.2794)
						)
					)
					(width 0)
					(fill yes)
				)
			)
		)
	)
	(footprint ""
		(layer "F.Cu")
		(at 113.919 -47.371 180)
		(property "Reference" "C362"
			(at 0 0 180)
			(layer "F.SilkS")
			(hide yes)
			(effects
				(font
					(size 1.27 1.27)
				)
			)
		)
		(property "Value" "SC47U16V0MX-GP"
			(at -0.00254 -4.78536 180)
			(unlocked yes)
			(layer "F.Fab")
			(hide yes)
			(effects
				(font
					(size 1.016 1.016)
					(thickness 0.1524)
				)
			)
		)
		(property "Device Type" "C1210H107"
			(at -0.00254 -6.38048 180)
			(unlocked yes)
			(layer "F.Fab")
			(hide yes)
			(effects
				(font
					(size 1.016 1.016)
					(thickness 0.1524)
				)
			)
		)
		(duplicate_pad_numbers_are_jumpers no)
		(fp_line
			(start 1.5748 2.3368)
			(end 1.5748 0.762)
			(stroke
				(width 0.1524)
				(type default)
			)
			(layer "F.SilkS")
		)
		(fp_line
			(start 1.5748 -0.762)
			(end 1.5748 -2.3368)
			(stroke
				(width 0.1524)
				(type default)
			)
			(layer "F.SilkS")
		)
		(fp_line
			(start 1.5748 -2.3368)
			(end -1.5748 -2.3368)
			(stroke
				(width 0.1524)
				(type default)
			)
			(layer "F.SilkS")
		)
		(fp_line
			(start -1.5748 2.3368)
			(end 1.5748 2.3368)
			(stroke
				(width 0.1524)
				(type default)
			)
			(layer "F.SilkS")
		)
		(fp_line
			(start -1.5748 0.762)
			(end -1.5748 2.3368)
			(stroke
				(width 0.1524)
				(type default)
			)
			(layer "F.SilkS")
		)
		(fp_line
			(start -1.5748 -2.3368)
			(end -1.5748 -0.762)
			(stroke
				(width 0.1524)
				(type default)
			)
			(layer "F.SilkS")
		)
		(fp_rect
			(start -1.651 2.413)
			(end 1.651 -2.413)
			(stroke
				(width 0)
				(type default)
			)
			(fill no)
			(layer "F.CrtYd")
		)
		(fp_poly
			(pts
				(xy 1.651 2.413) (xy 1.651 -2.413) (xy -1.651 -2.413) (xy -1.651 2.413)
			)
			(stroke
				(width 0)
				(type default)
			)
			(fill no)
			(layer "F.Fab")
		)
		(pad "1" smd rect
			(at 0 -1.4732 180)
			(size 2.794 1.397)
			(layers "F.Cu" "F.Mask" "F.Paste")
			(net "P12V")
		)
		(pad "2" smd rect
			(at 0 1.4732 180)
			(size 2.794 1.397)
			(layers "F.Cu" "F.Mask" "F.Paste")
			(net "GND")
		)
	)
	(footprint ""
		(layer "F.Cu")
		(at 9.684512 -95.791528 180)
		(property "Reference" "C357"
			(at 0 0 180)
			(layer "F.SilkS")
			(hide yes)
			(effects
				(font
					(size 1.27 1.27)
				)
			)
		)
		(property "Value" "SC220P50V3JN-GP"
			(at 0 -2.8194 180)
			(unlocked yes)
			(layer "F.Fab")
			(hide yes)
			(effects
				(font
					(size 1.016 1.016)
					(thickness 0.1524)
				)
			)
		)
		(property "Device Type" "C603H36"
			(at 0 -4.3434 180)
			(unlocked yes)
			(layer "F.Fab")
			(hide yes)
			(effects
				(font
					(size 1.016 1.016)
					(thickness 0.1524)
				)
			)
		)
		(duplicate_pad_numbers_are_jumpers no)
		(fp_line
			(start 0.508 0)
			(end -0.508 0)
			(stroke
				(width 0.2032)
				(type default)
			)
			(layer "F.SilkS")
		)
		(fp_rect
			(start -0.5842 1.3335)
			(end 0.5842 -1.3335)
			(stroke
				(width 0)
				(type default)
			)
			(fill no)
			(layer "F.CrtYd")
		)
		(fp_rect
			(start -0.5842 1.3335)
			(end 0.5842 -1.3335)
			(stroke
				(width 0)
				(type default)
			)
			(fill no)
			(layer "F.Fab")
		)
		(pad "1" smd custom
			(at 0 -0.762 180)
			(size 0.2159 0.2159)
			(layers "F.Cu" "F.Mask" "F.Paste")
			(net "I2C_C_SDA")
			(options
				(clearance outline)
				(anchor circle)
			)
			(primitives
				(gr_poly
					(pts
						(arc
							(start -0.3302 -0.4318)
							(mid -0.402042 -0.402042)
							(end -0.4318 -0.3302)
						)
						(arc
							(start -0.4318 0.3302)
							(mid -0.402042 0.402042)
							(end -0.3302 0.4318)
						)
						(arc
							(start 0.3302 0.4318)
							(mid 0.402042 0.402042)
							(end 0.4318 0.3302)
						)
						(arc
							(start 0.4318 -0.3302)
							(mid 0.402042 -0.402042)
							(end 0.3302 -0.4318)
						)
					)
					(width 0)
					(fill yes)
				)
			)
		)
		(pad "2" smd custom
			(at 0 0.762 180)
			(size 0.2159 0.2159)
			(layers "F.Cu" "F.Mask" "F.Paste")
			(net "GND")
			(options
				(clearance outline)
				(anchor circle)
			)
			(primitives
				(gr_poly
					(pts
						(arc
							(start -0.3302 -0.4318)
							(mid -0.402042 -0.402042)
							(end -0.4318 -0.3302)
						)
						(arc
							(start -0.4318 0.3302)
							(mid -0.402042 0.402042)
							(end -0.3302 0.4318)
						)
						(arc
							(start 0.3302 0.4318)
							(mid 0.402042 0.402042)
							(end 0.4318 0.3302)
						)
						(arc
							(start 0.4318 -0.3302)
							(mid 0.402042 -0.402042)
							(end 0.3302 -0.4318)
						)
					)
					(width 0)
					(fill yes)
				)
			)
		)
	)
	(footprint ""
		(layer "F.Cu")
		(at 156.972 -18.923)
		(property "Reference" "R483"
			(at 0 0 0)
			(layer "F.SilkS")
			(hide yes)
			(effects
				(font
					(size 1.27 1.27)
				)
			)
		)
		(property "Value" "2KR3F-L-GP"
			(at -0.0254 -2.5146 0)
			(unlocked yes)
			(layer "F.Fab")
			(hide yes)
			(effects
				(font
					(size 1.016 1.016)
					(thickness 0.1524)
				)
			)
		)
		(property "Device Type" "R603H22"
			(at -0.0254 -4.0386 0)
			(unlocked yes)
			(layer "F.Fab")
			(hide yes)
			(effects
				(font
					(size 1.016 1.016)
					(thickness 0.1524)
				)
			)
		)
		(duplicate_pad_numbers_are_jumpers no)
		(fp_line
			(start -0.4826 0)
			(end -0.2032 0)
			(stroke
				(width 0.2032)
				(type default)
			)
			(layer "F.SilkS")
		)
		(fp_line
			(start 0.2032 0)
			(end 0.4826 0)
			(stroke
				(width 0.2032)
				(type default)
			)
			(layer "F.SilkS")
		)
		(fp_rect
			(start -0.5842 1.3335)
			(end 0.5842 -1.3335)
			(stroke
				(width 0)
				(type default)
			)
			(fill no)
			(layer "F.CrtYd")
		)
		(fp_rect
			(start -0.5842 1.3335)
			(end 0.5842 -1.3335)
			(stroke
				(width 0)
				(type default)
			)
			(fill no)
			(layer "F.Fab")
		)
		(pad "1" smd custom
			(at 0 -0.762)
			(size 0.2159 0.2159)
			(layers "F.Cu" "F.Mask" "F.Paste")
			(net "P12V")
			(options
				(clearance outline)
				(anchor circle)
			)
			(primitives
				(gr_poly
					(pts
						(arc
							(start -0.3302 -0.4318)
							(mid -0.402042 -0.402042)
							(end -0.4318 -0.3302)
						)
						(arc
							(start -0.4318 0.3302)
							(mid -0.402042 0.402042)
							(end -0.3302 0.4318)
						)
						(arc
							(start 0.3302 0.4318)
							(mid 0.402042 0.402042)
							(end 0.4318 0.3302)
						)
						(arc
							(start 0.4318 -0.3302)
							(mid 0.402042 -0.402042)
							(end 0.3302 -0.4318)
						)
					)
					(width 0)
					(fill yes)
				)
			)
		)
		(pad "2" smd custom
			(at 0 0.762)
			(size 0.2159 0.2159)
			(layers "F.Cu" "F.Mask" "F.Paste")
			(net "TPS2490_LED")
			(options
				(clearance outline)
				(anchor circle)
			)
			(primitives
				(gr_poly
					(pts
						(arc
							(start -0.3302 -0.4318)
							(mid -0.402042 -0.402042)
							(end -0.4318 -0.3302)
						)
						(arc
							(start -0.4318 0.3302)
							(mid -0.402042 0.402042)
							(end -0.3302 0.4318)
						)
						(arc
							(start 0.3302 0.4318)
							(mid 0.402042 0.402042)
							(end 0.4318 0.3302)
						)
						(arc
							(start 0.4318 -0.3302)
							(mid 0.402042 -0.402042)
							(end 0.3302 -0.4318)
						)
					)
					(width 0)
					(fill yes)
				)
			)
		)
	)
	(footprint ""
		(layer "F.Cu")
		(at 0.050038 -49.179226 180)
		(property "Reference" "C348"
			(at 0 0 180)
			(layer "F.SilkS")
			(hide yes)
			(effects
				(font
					(size 1.27 1.27)
				)
			)
		)
		(property "Value" "SC10U25V5KX-GP"
			(at -0.0762 -6.1214 180)
			(unlocked yes)
			(layer "F.Fab")
			(hide yes)
			(effects
				(font
					(size 1.016 1.016)
					(thickness 0.1524)
				)
			)
		)
		(property "Device Type" "C805H56"
			(at -0.0762 -8.1534 180)
			(unlocked yes)
			(layer "F.Fab")
			(hide yes)
			(effects
				(font
					(size 1.016 1.016)
					(thickness 0.1524)
				)
			)
		)
		(duplicate_pad_numbers_are_jumpers no)
		(fp_line
			(start 0.635 0)
			(end -0.635 0)
			(stroke
				(width 0.508)
				(type default)
			)
			(layer "F.SilkS")
		)
		(fp_rect
			(start -0.9652 1.778)
			(end 0.9652 -1.778)
			(stroke
				(width 0)
				(type default)
			)
			(fill no)
			(layer "F.CrtYd")
		)
		(fp_poly
			(pts
				(xy -0.9652 -1.778) (xy 0.9652 -1.778) (xy 0.9652 1.778) (xy -0.9652 1.778)
			)
			(stroke
				(width 0)
				(type default)
			)
			(fill no)
			(layer "F.Fab")
		)
		(pad "1" smd rect
			(at 0 -0.9652 180)
			(size 1.397 1.143)
			(layers "F.Cu" "F.Mask" "F.Paste")
			(net "P12V")
		)
		(pad "2" smd rect
			(at 0 0.9652 180)
			(size 1.397 1.143)
			(layers "F.Cu" "F.Mask" "F.Paste")
			(net "GND")
		)
	)
	(footprint ""
		(layer "F.Cu")
		(at 155.650692 -103.082344)
		(property "Reference" "PR65"
			(at 0 0 0)
			(layer "F.SilkS")
			(hide yes)
			(effects
				(font
					(size 1.27 1.27)
				)
			)
		)
		(property "Value" "0R3J-0-U-GP"
			(at -0.0254 -2.5146 0)
			(unlocked yes)
			(layer "F.Fab")
			(hide yes)
			(effects
				(font
					(size 1.016 1.016)
					(thickness 0.1524)
				)
			)
		)
		(property "Device Type" "R603H22"
			(at -0.0254 -4.0386 0)
			(unlocked yes)
			(layer "F.Fab")
			(hide yes)
			(effects
				(font
					(size 1.016 1.016)
					(thickness 0.1524)
				)
			)
		)
		(duplicate_pad_numbers_are_jumpers no)
		(fp_line
			(start -0.4826 0)
			(end -0.2032 0)
			(stroke
				(width 0.2032)
				(type default)
			)
			(layer "F.SilkS")
		)
		(fp_line
			(start 0.2032 0)
			(end 0.4826 0)
			(stroke
				(width 0.2032)
				(type default)
			)
			(layer "F.SilkS")
		)
		(fp_rect
			(start -0.5842 1.3335)
			(end 0.5842 -1.3335)
			(stroke
				(width 0)
				(type default)
			)
			(fill no)
			(layer "F.CrtYd")
		)
		(fp_rect
			(start -0.5842 1.3335)
			(end 0.5842 -1.3335)
			(stroke
				(width 0)
				(type default)
			)
			(fill no)
			(layer "F.Fab")
		)
		(pad "1" smd custom
			(at 0 -0.762)
			(size 0.2159 0.2159)
			(layers "F.Cu" "F.Mask" "F.Paste")
			(net "P3V3")
			(options
				(clearance outline)
				(anchor circle)
			)
			(primitives
				(gr_poly
					(pts
						(arc
							(start -0.3302 -0.4318)
							(mid -0.402042 -0.402042)
							(end -0.4318 -0.3302)
						)
						(arc
							(start -0.4318 0.3302)
							(mid -0.402042 0.402042)
							(end -0.3302 0.4318)
						)
						(arc
							(start 0.3302 0.4318)
							(mid 0.402042 0.402042)
							(end 0.4318 0.3302)
						)
						(arc
							(start 0.4318 -0.3302)
							(mid 0.402042 -0.402042)
							(end 0.3302 -0.4318)
						)
					)
					(width 0)
					(fill yes)
				)
			)
		)
		(pad "2" smd custom
			(at 0 0.762)
			(size 0.2159 0.2159)
			(layers "F.Cu" "F.Mask" "F.Paste")
			(net "DETECTOR_C")
			(options
				(clearance outline)
				(anchor circle)
			)
			(primitives
				(gr_poly
					(pts
						(arc
							(start -0.3302 -0.4318)
							(mid -0.402042 -0.402042)
							(end -0.4318 -0.3302)
						)
						(arc
							(start -0.4318 0.3302)
							(mid -0.402042 0.402042)
							(end -0.3302 0.4318)
						)
						(arc
							(start 0.3302 0.4318)
							(mid 0.402042 0.402042)
							(end 0.4318 0.3302)
						)
						(arc
							(start 0.4318 -0.3302)
							(mid 0.402042 -0.402042)
							(end 0.3302 -0.4318)
						)
					)
					(width 0)
					(fill yes)
				)
			)
		)
	)
	(footprint ""
		(layer "F.Cu")
		(at 9.372092 -85.835744 90)
		(property "Reference" "R385"
			(at 0 0 90)
			(layer "F.SilkS")
			(hide yes)
			(effects
				(font
					(size 1.27 1.27)
				)
			)
		)
		(property "Value" "0R2J-2-GP"
			(at 0.064008 -3.993896 90)
			(unlocked yes)
			(layer "F.Fab")
			(hide yes)
			(effects
				(font
					(size 1.016 1.016)
					(thickness 0.1524)
				)
			)
		)
		(property "Device Type" "R402H16"
			(at 0.064008 -5.517896 90)
			(unlocked yes)
			(layer "F.Fab")
			(hide yes)
			(effects
				(font
					(size 1.016 1.016)
					(thickness 0.1524)
				)
			)
		)
		(duplicate_pad_numbers_are_jumpers no)
		(fp_line
			(start 0.508 -0.9398)
			(end -0.508 -0.9398)
			(stroke
				(width 0.1524)
				(type default)
			)
			(layer "F.SilkS")
		)
		(fp_line
			(start -0.508 -0.9398)
			(end -0.508 0.9398)
			(stroke
				(width 0.1524)
				(type default)
			)
			(layer "F.SilkS")
		)
		(fp_rect
			(start -0.508 0.9398)
			(end 0.508 -0.9398)
			(stroke
				(width 0)
				(type default)
			)
			(fill no)
			(layer "F.CrtYd")
		)
		(fp_rect
			(start -0.508 0.9398)
			(end 0.508 -0.9398)
			(stroke
				(width 0)
				(type default)
			)
			(fill no)
			(layer "F.Fab")
		)
		(pad "1" smd custom
			(at 0 -0.4445 90)
			(size 0.1397 0.1397)
			(layers "F.Cu" "F.Mask" "F.Paste")
			(net "PWM_EXP_B")
			(options
				(clearance outline)
				(anchor circle)
			)
			(primitives
				(gr_poly
					(pts
						(arc
							(start -0.1778 -0.2794)
							(mid -0.249642 -0.249642)
							(end -0.2794 -0.1778)
						)
						(arc
							(start -0.2794 0.1778)
							(mid -0.249642 0.249642)
							(end -0.1778 0.2794)
						)
						(arc
							(start 0.1778 0.2794)
							(mid 0.249642 0.249642)
							(end 0.2794 0.1778)
						)
						(arc
							(start 0.2794 -0.1778)
							(mid 0.249642 -0.249642)
							(end 0.1778 -0.2794)
						)
					)
					(width 0)
					(fill yes)
				)
			)
		)
		(pad "2" smd custom
			(at 0 0.4445 90)
			(size 0.1397 0.1397)
			(layers "F.Cu" "F.Mask" "F.Paste")
			(net "PWM_EXP_B_OUT")
			(options
				(clearance outline)
				(anchor circle)
			)
			(primitives
				(gr_poly
					(pts
						(arc
							(start -0.1778 -0.2794)
							(mid -0.249642 -0.249642)
							(end -0.2794 -0.1778)
						)
						(arc
							(start -0.2794 0.1778)
							(mid -0.249642 0.249642)
							(end -0.1778 0.2794)
						)
						(arc
							(start 0.1778 0.2794)
							(mid 0.249642 0.249642)
							(end 0.2794 0.1778)
						)
						(arc
							(start 0.2794 -0.1778)
							(mid 0.249642 -0.249642)
							(end 0.1778 -0.2794)
						)
					)
					(width 0)
					(fill yes)
				)
			)
		)
	)
	(footprint ""
		(layer "F.Cu")
		(at 17.218914 -92.751402 -90)
		(property "Reference" "R485"
			(at 0 0 270)
			(layer "F.SilkS")
			(hide yes)
			(effects
				(font
					(size 1.27 1.27)
				)
			)
		)
		(property "Value" "0R2J-2-GP"
			(at 0.064008 -3.993896 270)
			(unlocked yes)
			(layer "F.Fab")
			(hide yes)
			(effects
				(font
					(size 1.016 1.016)
					(thickness 0.1524)
				)
			)
		)
		(property "Device Type" "R402H16"
			(at 0.064008 -5.517896 270)
			(unlocked yes)
			(layer "F.Fab")
			(hide yes)
			(effects
				(font
					(size 1.016 1.016)
					(thickness 0.1524)
				)
			)
		)
		(duplicate_pad_numbers_are_jumpers no)
		(fp_line
			(start -0.508 -0.9398)
			(end -0.508 0.9398)
			(stroke
				(width 0.1524)
				(type default)
			)
			(layer "F.SilkS")
		)
		(fp_line
			(start 0.508 -0.9398)
			(end -0.508 -0.9398)
			(stroke
				(width 0.1524)
				(type default)
			)
			(layer "F.SilkS")
		)
		(fp_rect
			(start -0.508 0.9398)
			(end 0.508 -0.9398)
			(stroke
				(width 0)
				(type default)
			)
			(fill no)
			(layer "F.CrtYd")
		)
		(fp_rect
			(start -0.508 0.9398)
			(end 0.508 -0.9398)
			(stroke
				(width 0)
				(type default)
			)
			(fill no)
			(layer "F.Fab")
		)
		(pad "1" smd custom
			(at 0 -0.4445 270)
			(size 0.1397 0.1397)
			(layers "F.Cu" "F.Mask" "F.Paste")
			(net "I2C_C_BUF_SCL")
			(options
				(clearance outline)
				(anchor circle)
			)
			(primitives
				(gr_poly
					(pts
						(arc
							(start -0.1778 -0.2794)
							(mid -0.249642 -0.249642)
							(end -0.2794 -0.1778)
						)
						(arc
							(start -0.2794 0.1778)
							(mid -0.249642 0.249642)
							(end -0.1778 0.2794)
						)
						(arc
							(start 0.1778 0.2794)
							(mid 0.249642 0.249642)
							(end 0.2794 0.1778)
						)
						(arc
							(start 0.2794 -0.1778)
							(mid 0.249642 -0.249642)
							(end 0.1778 -0.2794)
						)
					)
					(width 0)
					(fill yes)
				)
			)
		)
		(pad "2" smd custom
			(at 0 0.4445 270)
			(size 0.1397 0.1397)
			(layers "F.Cu" "F.Mask" "F.Paste")
			(net "I2C_C_BUF_SCLIN")
			(options
				(clearance outline)
				(anchor circle)
			)
			(primitives
				(gr_poly
					(pts
						(arc
							(start -0.1778 -0.2794)
							(mid -0.249642 -0.249642)
							(end -0.2794 -0.1778)
						)
						(arc
							(start -0.2794 0.1778)
							(mid -0.249642 0.249642)
							(end -0.1778 0.2794)
						)
						(arc
							(start 0.1778 0.2794)
							(mid 0.249642 0.249642)
							(end 0.2794 0.1778)
						)
						(arc
							(start 0.2794 -0.1778)
							(mid 0.249642 -0.249642)
							(end 0.1778 -0.2794)
						)
					)
					(width 0)
					(fill yes)
				)
			)
		)
	)
	(footprint ""
		(layer "F.Cu")
		(at 133.223 -81.788 -90)
		(property "Reference" "R482"
			(at 0 0 270)
			(layer "F.SilkS")
			(hide yes)
			(effects
				(font
					(size 1.27 1.27)
				)
			)
		)
		(property "Value" "0R2J-2-GP"
			(at 0.064008 -3.993896 270)
			(unlocked yes)
			(layer "F.Fab")
			(hide yes)
			(effects
				(font
					(size 1.016 1.016)
					(thickness 0.1524)
				)
			)
		)
		(property "Device Type" "R402H16"
			(at 0.064008 -5.517896 270)
			(unlocked yes)
			(layer "F.Fab")
			(hide yes)
			(effects
				(font
					(size 1.016 1.016)
					(thickness 0.1524)
				)
			)
		)
		(duplicate_pad_numbers_are_jumpers no)
		(fp_line
			(start -0.508 -0.9398)
			(end -0.508 0.9398)
			(stroke
				(width 0.1524)
				(type default)
			)
			(layer "F.SilkS")
		)
		(fp_line
			(start 0.508 -0.9398)
			(end -0.508 -0.9398)
			(stroke
				(width 0.1524)
				(type default)
			)
			(layer "F.SilkS")
		)
		(fp_rect
			(start -0.508 0.9398)
			(end 0.508 -0.9398)
			(stroke
				(width 0)
				(type default)
			)
			(fill no)
			(layer "F.CrtYd")
		)
		(fp_rect
			(start -0.508 0.9398)
			(end 0.508 -0.9398)
			(stroke
				(width 0)
				(type default)
			)
			(fill no)
			(layer "F.Fab")
		)
		(pad "1" smd custom
			(at 0 -0.4445 270)
			(size 0.1397 0.1397)
			(layers "F.Cu" "F.Mask" "F.Paste")
			(net "TRAY PRESENT_OUT#_C")
			(options
				(clearance outline)
				(anchor circle)
			)
			(primitives
				(gr_poly
					(pts
						(arc
							(start -0.1778 -0.2794)
							(mid -0.249642 -0.249642)
							(end -0.2794 -0.1778)
						)
						(arc
							(start -0.2794 0.1778)
							(mid -0.249642 0.249642)
							(end -0.1778 0.2794)
						)
						(arc
							(start 0.1778 0.2794)
							(mid 0.249642 0.249642)
							(end 0.2794 0.1778)
						)
						(arc
							(start 0.2794 -0.1778)
							(mid 0.249642 -0.249642)
							(end 0.1778 -0.2794)
						)
					)
					(width 0)
					(fill yes)
				)
			)
		)
		(pad "2" smd custom
			(at 0 0.4445 270)
			(size 0.1397 0.1397)
			(layers "F.Cu" "F.Mask" "F.Paste")
			(net "TRAY_MOSFET_G")
			(options
				(clearance outline)
				(anchor circle)
			)
			(primitives
				(gr_poly
					(pts
						(arc
							(start -0.1778 -0.2794)
							(mid -0.249642 -0.249642)
							(end -0.2794 -0.1778)
						)
						(arc
							(start -0.2794 0.1778)
							(mid -0.249642 0.249642)
							(end -0.1778 0.2794)
						)
						(arc
							(start 0.1778 0.2794)
							(mid 0.249642 0.249642)
							(end 0.2794 0.1778)
						)
						(arc
							(start 0.2794 -0.1778)
							(mid 0.249642 -0.249642)
							(end 0.1778 -0.2794)
						)
					)
					(width 0)
					(fill yes)
				)
			)
		)
	)
	(footprint ""
		(layer "F.Cu")
		(at 17.233138 -94.990666 90)
		(property "Reference" "R481"
			(at 0 0 90)
			(layer "F.SilkS")
			(hide yes)
			(effects
				(font
					(size 1.27 1.27)
				)
			)
		)
		(property "Value" "0R2J-2-GP"
			(at 0.064008 -3.993896 90)
			(unlocked yes)
			(layer "F.Fab")
			(hide yes)
			(effects
				(font
					(size 1.016 1.016)
					(thickness 0.1524)
				)
			)
		)
		(property "Device Type" "R402H16"
			(at 0.064008 -5.517896 90)
			(unlocked yes)
			(layer "F.Fab")
			(hide yes)
			(effects
				(font
					(size 1.016 1.016)
					(thickness 0.1524)
				)
			)
		)
		(duplicate_pad_numbers_are_jumpers no)
		(fp_line
			(start 0.508 -0.9398)
			(end -0.508 -0.9398)
			(stroke
				(width 0.1524)
				(type default)
			)
			(layer "F.SilkS")
		)
		(fp_line
			(start -0.508 -0.9398)
			(end -0.508 0.9398)
			(stroke
				(width 0.1524)
				(type default)
			)
			(layer "F.SilkS")
		)
		(fp_rect
			(start -0.508 0.9398)
			(end 0.508 -0.9398)
			(stroke
				(width 0)
				(type default)
			)
			(fill no)
			(layer "F.CrtYd")
		)
		(fp_rect
			(start -0.508 0.9398)
			(end 0.508 -0.9398)
			(stroke
				(width 0)
				(type default)
			)
			(fill no)
			(layer "F.Fab")
		)
		(pad "1" smd custom
			(at 0 -0.4445 90)
			(size 0.1397 0.1397)
			(layers "F.Cu" "F.Mask" "F.Paste")
			(net "I2C_C_SDA")
			(options
				(clearance outline)
				(anchor circle)
			)
			(primitives
				(gr_poly
					(pts
						(arc
							(start -0.1778 -0.2794)
							(mid -0.249642 -0.249642)
							(end -0.2794 -0.1778)
						)
						(arc
							(start -0.2794 0.1778)
							(mid -0.249642 0.249642)
							(end -0.1778 0.2794)
						)
						(arc
							(start 0.1778 0.2794)
							(mid 0.249642 0.249642)
							(end 0.2794 0.1778)
						)
						(arc
							(start 0.2794 -0.1778)
							(mid 0.249642 -0.249642)
							(end 0.1778 -0.2794)
						)
					)
					(width 0)
					(fill yes)
				)
			)
		)
		(pad "2" smd custom
			(at 0 0.4445 90)
			(size 0.1397 0.1397)
			(layers "F.Cu" "F.Mask" "F.Paste")
			(net "I2C_C_BUF_SDA")
			(options
				(clearance outline)
				(anchor circle)
			)
			(primitives
				(gr_poly
					(pts
						(arc
							(start -0.1778 -0.2794)
							(mid -0.249642 -0.249642)
							(end -0.2794 -0.1778)
						)
						(arc
							(start -0.2794 0.1778)
							(mid -0.249642 0.249642)
							(end -0.1778 0.2794)
						)
						(arc
							(start 0.1778 0.2794)
							(mid 0.249642 0.249642)
							(end 0.2794 0.1778)
						)
						(arc
							(start 0.2794 -0.1778)
							(mid 0.249642 -0.249642)
							(end 0.1778 -0.2794)
						)
					)
					(width 0)
					(fill yes)
				)
			)
		)
	)
	(footprint ""
		(layer "F.Cu")
		(at 10.940288 -93.356938)
		(property "Reference" "R484"
			(at 0 0 0)
			(layer "F.SilkS")
			(hide yes)
			(effects
				(font
					(size 1.27 1.27)
				)
			)
		)
		(property "Value" "0R2J-2-GP"
			(at 0.064008 -3.993896 0)
			(unlocked yes)
			(layer "F.Fab")
			(hide yes)
			(effects
				(font
					(size 1.016 1.016)
					(thickness 0.1524)
				)
			)
		)
		(property "Device Type" "R402H16"
			(at 0.064008 -5.517896 0)
			(unlocked yes)
			(layer "F.Fab")
			(hide yes)
			(effects
				(font
					(size 1.016 1.016)
					(thickness 0.1524)
				)
			)
		)
		(duplicate_pad_numbers_are_jumpers no)
		(fp_line
			(start -0.508 -0.9398)
			(end -0.508 0.9398)
			(stroke
				(width 0.1524)
				(type default)
			)
			(layer "F.SilkS")
		)
		(fp_line
			(start 0.508 -0.9398)
			(end -0.508 -0.9398)
			(stroke
				(width 0.1524)
				(type default)
			)
			(layer "F.SilkS")
		)
		(fp_rect
			(start -0.508 0.9398)
			(end 0.508 -0.9398)
			(stroke
				(width 0)
				(type default)
			)
			(fill no)
			(layer "F.CrtYd")
		)
		(fp_rect
			(start -0.508 0.9398)
			(end 0.508 -0.9398)
			(stroke
				(width 0)
				(type default)
			)
			(fill no)
			(layer "F.Fab")
		)
		(pad "1" smd custom
			(at 0 -0.4445)
			(size 0.1397 0.1397)
			(layers "F.Cu" "F.Mask" "F.Paste")
			(net "I2C_C_SCL")
			(options
				(clearance outline)
				(anchor circle)
			)
			(primitives
				(gr_poly
					(pts
						(arc
							(start -0.1778 -0.2794)
							(mid -0.249642 -0.249642)
							(end -0.2794 -0.1778)
						)
						(arc
							(start -0.2794 0.1778)
							(mid -0.249642 0.249642)
							(end -0.1778 0.2794)
						)
						(arc
							(start 0.1778 0.2794)
							(mid 0.249642 0.249642)
							(end 0.2794 0.1778)
						)
						(arc
							(start 0.2794 -0.1778)
							(mid 0.249642 -0.249642)
							(end 0.1778 -0.2794)
						)
					)
					(width 0)
					(fill yes)
				)
			)
		)
		(pad "2" smd custom
			(at 0 0.4445)
			(size 0.1397 0.1397)
			(layers "F.Cu" "F.Mask" "F.Paste")
			(net "I2C_C_BUF_SCLOUT")
			(options
				(clearance outline)
				(anchor circle)
			)
			(primitives
				(gr_poly
					(pts
						(arc
							(start -0.1778 -0.2794)
							(mid -0.249642 -0.249642)
							(end -0.2794 -0.1778)
						)
						(arc
							(start -0.2794 0.1778)
							(mid -0.249642 0.249642)
							(end -0.1778 0.2794)
						)
						(arc
							(start 0.1778 0.2794)
							(mid 0.249642 0.249642)
							(end 0.2794 0.1778)
						)
						(arc
							(start 0.2794 -0.1778)
							(mid 0.249642 -0.249642)
							(end 0.1778 -0.2794)
						)
					)
					(width 0)
					(fill yes)
				)
			)
		)
	)
	(footprint ""
		(layer "F.Cu")
		(at 147.660106 -110.000034)
		(property "Reference" "SW1"
			(at 0 0 0)
			(layer "F.SilkS")
			(hide yes)
			(effects
				(font
					(size 1.27 1.27)
				)
			)
		)
		(property "Value" "SW-PUSH-3P-3-GP"
			(at 18.9357 -6.1341 0)
			(unlocked yes)
			(layer "F.Fab")
			(hide yes)
			(effects
				(font
					(size 1.016 1.016)
					(thickness 0.1524)
				)
			)
		)
		(property "Device Type" "MS-B1PL-10"
			(at 18.9357 -7.6581 0)
			(unlocked yes)
			(layer "F.Fab")
			(hide yes)
			(effects
				(font
					(size 1.016 1.016)
					(thickness 0.1524)
				)
			)
		)
		(duplicate_pad_numbers_are_jumpers no)
		(fp_line
			(start -6.6294 0.3302)
			(end -6.096 0.3302)
			(stroke
				(width 0.1524)
				(type default)
			)
			(layer "F.SilkS")
		)
		(fp_line
			(start -6.6294 2.8575)
			(end -6.6294 0.3302)
			(stroke
				(width 0.1524)
				(type default)
			)
			(layer "F.SilkS")
		)
		(fp_line
			(start -6.096 -2.8575)
			(end 4.6228 -2.8575)
			(stroke
				(width 0.1524)
				(type default)
			)
			(layer "F.SilkS")
		)
		(fp_line
			(start -6.096 0.3302)
			(end -6.096 -2.8575)
			(stroke
				(width 0.1524)
				(type default)
			)
			(layer "F.SilkS")
		)
		(fp_line
			(start 4.6228 -3.3528)
			(end 19.9136 -3.3528)
			(stroke
				(width 0.1524)
				(type default)
			)
			(layer "F.SilkS")
		)
		(fp_line
			(start 4.6228 -2.8575)
			(end 4.6228 -3.3528)
			(stroke
				(width 0.1524)
				(type default)
			)
			(layer "F.SilkS")
		)
		(fp_line
			(start 5.8928 2.8575)
			(end -6.6294 2.8575)
			(stroke
				(width 0.1524)
				(type default)
			)
			(layer "F.SilkS")
		)
		(fp_line
			(start 5.8928 3.3528)
			(end 5.8928 2.8575)
			(stroke
				(width 0.1524)
				(type default)
			)
			(layer "F.SilkS")
		)
		(fp_line
			(start 19.9136 -3.3528)
			(end 19.9136 3.3528)
			(stroke
				(width 0.1524)
				(type default)
			)
			(layer "F.SilkS")
		)
		(fp_line
			(start 19.9136 3.3528)
			(end 5.8928 3.3528)
			(stroke
				(width 0.1524)
				(type default)
			)
			(layer "F.SilkS")
		)
		(fp_circle
			(center -5.5499 1.400048)
			(end -4.3815 1.400048)
			(stroke
				(width 0.3048)
				(type default)
			)
			(fill no)
			(layer "F.SilkS")
		)
		(fp_circle
			(center -2.500122 0)
			(end -1.484122 0)
			(stroke
				(width 0.3048)
				(type default)
			)
			(fill no)
			(layer "F.SilkS")
		)
		(fp_circle
			(center 0 0)
			(end 1.016 0)
			(stroke
				(width 0.3048)
				(type default)
			)
			(fill no)
			(layer "F.SilkS")
		)
		(fp_circle
			(center 2.500122 0)
			(end 3.516122 0)
			(stroke
				(width 0.3048)
				(type default)
			)
			(fill no)
			(layer "F.SilkS")
		)
		(fp_circle
			(center 5.700014 -2.29997)
			(end 6.868414 -2.29997)
			(stroke
				(width 0.3048)
				(type default)
			)
			(fill no)
			(layer "F.SilkS")
		)
		(fp_poly
			(pts
				(xy -5.842 -2.6035) (xy 6.1468 -2.6035) (xy 6.1468 -3.0988) (xy 19.6596 -3.0988) (xy 19.6596 3.0988)
				(xy 6.1468 3.0988) (xy 6.1468 2.6035) (xy -5.842 2.6035)
			)
			(stroke
				(width 0)
				(type default)
			)
			(fill no)
			(layer "F.CrtYd")
		)
		(fp_poly
			(pts
				(xy 5.6388 3.6068) (xy 5.6388 3.1115) (xy -6.8834 3.1115) (xy -6.8834 0.0762) (xy -6.35 0.0762)
				(xy -6.35 -3.1115) (xy 4.3688 -3.1115) (xy 4.3688 -3.6068) (xy 20.1676 -3.6068) (xy 20.1676 -0.00635)
				(xy 19.6596 -0.00635) (xy 19.6596 -3.0988) (xy 6.1468 -3.0988) (xy 6.1468 -2.6035) (xy -5.842 -2.6035)
				(xy -5.842 2.6035) (xy 6.1468 2.6035) (xy 6.1468 3.0988) (xy 19.6596 3.0988) (xy 19.6596 0.00635)
				(xy 20.1676 0.00635) (xy 20.1676 3.6068)
			)
			(stroke
				(width 0)
				(type default)
			)
			(fill no)
			(layer "F.CrtYd")
		)
		(fp_poly
			(pts
				(xy 5.6388 3.6068) (xy 5.6388 3.1115) (xy -6.8834 3.1115) (xy -6.8834 0.0762) (xy -6.35 0.0762)
				(xy -6.35 -3.1115) (xy 4.3688 -3.1115) (xy 4.3688 -3.6068) (xy 20.1676 -3.6068) (xy 20.1676 3.6068)
			)
			(stroke
				(width 0)
				(type default)
			)
			(fill no)
			(layer "F.Fab")
		)
		(pad "1" thru_hole circle
			(at 2.500122 0)
			(size 1.3208 1.3208)
			(drill 0.9144)
			(layers "*.Cu" "*.Mask")
			(remove_unused_layers no)
			(net "TPS2490_EN1")
			(clearance 0.1524)
			(thermal_gap 0.1524)
		)
		(pad "2" thru_hole circle
			(at 0 0)
			(size 1.3208 1.3208)
			(drill 0.9144)
			(layers "*.Cu" "*.Mask")
			(remove_unused_layers no)
			(net "TPS2490_EN2")
			(clearance 0.1524)
			(thermal_gap 0.1524)
		)
		(pad "3" thru_hole circle
			(at -2.500122 0)
			(size 1.3208 1.3208)
			(drill 0.9144)
			(layers "*.Cu" "*.Mask")
			(remove_unused_layers no)
			(net "TPS2490_DISABLE")
			(clearance 0.1524)
			(thermal_gap 0.1524)
		)
		(pad "4" thru_hole circle
			(at 5.700014 -2.29997)
			(size 1.6256 1.6256)
			(drill 1.2192)
			(layers "*.Cu" "*.Mask")
			(remove_unused_layers no)
			(net "GND")
			(clearance 0.1524)
			(thermal_gap 0.1524)
		)
		(pad "5" thru_hole circle
			(at -5.5499 1.400048)
			(size 1.6256 1.6256)
			(drill 1.2192)
			(layers "*.Cu" "*.Mask")
			(remove_unused_layers no)
			(net "GND")
			(clearance 0.1524)
			(thermal_gap 0.1524)
		)
		(zone
			(layer "F.Cu")
			(hatch none 0.5)
			(connect_pads
				(clearance 0)
			)
			(min_thickness 0.25)
			(keepout
				(tracks allowed)
				(vias not_allowed)
				(pads allowed)
				(copperpour not_allowed)
				(footprints allowed)
			)
			(placement
				(enabled no)
				(sheetname "")
			)
			(fill
				(thermal_gap 0.5)
				(thermal_bridge_width 0.5)
				(island_removal_mode 0)
			)
			(polygon
				(pts
					(xy 141.683232 -109.412786) (xy 142.53718 -109.412786) (xy 142.53718 -110.076996) (xy 141.683232 -110.076996)
				)
			)
		)
		(zone
			(layer "F.Cu")
			(hatch none 0.5)
			(connect_pads
				(clearance 0)
			)
			(min_thickness 0.25)
			(keepout
				(tracks not_allowed)
				(vias allowed)
				(pads allowed)
				(copperpour not_allowed)
				(footprints allowed)
			)
			(placement
				(enabled no)
				(sheetname "")
			)
			(fill
				(thermal_gap 0.5)
				(thermal_bridge_width 0.5)
				(island_removal_mode 0)
			)
			(polygon
				(pts
					(xy 141.683232 -109.412786) (xy 142.53718 -109.412786) (xy 142.53718 -110.076996) (xy 141.683232 -110.076996)
				)
			)
		)
		(zone
			(layer "F.Cu")
			(hatch none 0.5)
			(connect_pads
				(clearance 0)
			)
			(min_thickness 0.25)
			(keepout
				(tracks allowed)
				(vias not_allowed)
				(pads allowed)
				(copperpour not_allowed)
				(footprints allowed)
			)
			(placement
				(enabled no)
				(sheetname "")
			)
			(fill
				(thermal_gap 0.5)
				(thermal_bridge_width 0.5)
				(island_removal_mode 0)
			)
			(polygon
				(pts
					(xy 142.332202 -111.87303) (xy 143.637 -111.87303) (xy 143.637 -112.777778) (xy 142.332202 -112.777778)
				)
			)
		)
		(zone
			(layer "F.Cu")
			(hatch none 0.5)
			(connect_pads
				(clearance 0)
			)
			(min_thickness 0.25)
			(keepout
				(tracks not_allowed)
				(vias allowed)
				(pads allowed)
				(copperpour not_allowed)
				(footprints allowed)
			)
			(placement
				(enabled no)
				(sheetname "")
			)
			(fill
				(thermal_gap 0.5)
				(thermal_bridge_width 0.5)
				(island_removal_mode 0)
			)
			(polygon
				(pts
					(xy 142.332202 -111.87303) (xy 143.637 -111.87303) (xy 143.637 -112.777778) (xy 142.332202 -112.777778)
				)
			)
		)
		(zone
			(layer "F.Cu")
			(hatch none 0.5)
			(connect_pads
				(clearance 0)
			)
			(min_thickness 0.25)
			(keepout
				(tracks allowed)
				(vias not_allowed)
				(pads allowed)
				(copperpour not_allowed)
				(footprints allowed)
			)
			(placement
				(enabled no)
				(sheetname "")
			)
			(fill
				(thermal_gap 0.5)
				(thermal_bridge_width 0.5)
				(island_removal_mode 0)
			)
			(polygon
				(pts
					(xy 142.923006 -107.22229) (xy 143.637 -107.22229) (xy 143.637 -108.127038) (xy 142.923006 -108.127038)
				)
			)
		)
		(zone
			(layer "F.Cu")
			(hatch none 0.5)
			(connect_pads
				(clearance 0)
			)
			(min_thickness 0.25)
			(keepout
				(tracks not_allowed)
				(vias allowed)
				(pads allowed)
				(copperpour not_allowed)
				(footprints allowed)
			)
			(placement
				(enabled no)
				(sheetname "")
			)
			(fill
				(thermal_gap 0.5)
				(thermal_bridge_width 0.5)
				(island_removal_mode 0)
			)
			(polygon
				(pts
					(xy 142.923006 -107.22229) (xy 143.637 -107.22229) (xy 143.637 -108.127038) (xy 142.923006 -108.127038)
				)
			)
		)
		(zone
			(layer "F.Cu")
			(hatch none 0.5)
			(connect_pads
				(clearance 0)
			)
			(min_thickness 0.25)
			(keepout
				(tracks allowed)
				(vias not_allowed)
				(pads allowed)
				(copperpour not_allowed)
				(footprints allowed)
			)
			(placement
				(enabled no)
				(sheetname "")
			)
			(fill
				(thermal_gap 0.5)
				(thermal_bridge_width 0.5)
				(island_removal_mode 0)
			)
			(polygon
				(pts
					(xy 151.908002 -111.87303) (xy 152.54732 -111.87303) (xy 152.54732 -112.777778) (xy 151.908002 -112.777778)
				)
			)
		)
		(zone
			(layer "F.Cu")
			(hatch none 0.5)
			(connect_pads
				(clearance 0)
			)
			(min_thickness 0.25)
			(keepout
				(tracks not_allowed)
				(vias allowed)
				(pads allowed)
				(copperpour not_allowed)
				(footprints allowed)
			)
			(placement
				(enabled no)
				(sheetname "")
			)
			(fill
				(thermal_gap 0.5)
				(thermal_bridge_width 0.5)
				(island_removal_mode 0)
			)
			(polygon
				(pts
					(xy 151.908002 -111.87303) (xy 152.54732 -111.87303) (xy 152.54732 -112.777778) (xy 151.908002 -112.777778)
				)
			)
		)
		(zone
			(layer "F.Cu")
			(hatch none 0.5)
			(connect_pads
				(clearance 0)
			)
			(min_thickness 0.25)
			(keepout
				(tracks allowed)
				(vias not_allowed)
				(pads allowed)
				(copperpour not_allowed)
				(footprints allowed)
			)
			(placement
				(enabled no)
				(sheetname "")
			)
			(fill
				(thermal_gap 0.5)
				(thermal_bridge_width 0.5)
				(island_removal_mode 0)
			)
			(polygon
				(pts
					(xy 151.908002 -107.22229) (xy 153.162 -107.22229) (xy 153.162 -108.127038) (xy 151.908002 -108.127038)
				)
			)
		)
		(zone
			(layer "F.Cu")
			(hatch none 0.5)
			(connect_pads
				(clearance 0)
			)
			(min_thickness 0.25)
			(keepout
				(tracks not_allowed)
				(vias allowed)
				(pads allowed)
				(copperpour not_allowed)
				(footprints allowed)
			)
			(placement
				(enabled no)
				(sheetname "")
			)
			(fill
				(thermal_gap 0.5)
				(thermal_bridge_width 0.5)
				(island_removal_mode 0)
			)
			(polygon
				(pts
					(xy 151.908002 -107.22229) (xy 153.162 -107.22229) (xy 153.162 -108.127038) (xy 151.908002 -108.127038)
				)
			)
		)
	)
	(footprint ""
		(layer "F.Cu")
		(at 137.795 -66.286634)
		(property "Reference" "C359"
			(at 0 0 0)
			(layer "F.SilkS")
			(hide yes)
			(effects
				(font
					(size 1.27 1.27)
				)
			)
		)
		(property "Value" "SC220P50V3JN-GP"
			(at 0 -2.8194 0)
			(unlocked yes)
			(layer "F.Fab")
			(hide yes)
			(effects
				(font
					(size 1.016 1.016)
					(thickness 0.1524)
				)
			)
		)
		(property "Device Type" "C603H36"
			(at 0 -4.3434 0)
			(unlocked yes)
			(layer "F.Fab")
			(hide yes)
			(effects
				(font
					(size 1.016 1.016)
					(thickness 0.1524)
				)
			)
		)
		(duplicate_pad_numbers_are_jumpers no)
		(fp_line
			(start 0.508 0)
			(end -0.508 0)
			(stroke
				(width 0.2032)
				(type default)
			)
			(layer "F.SilkS")
		)
		(fp_rect
			(start -0.5842 1.3335)
			(end 0.5842 -1.3335)
			(stroke
				(width 0)
				(type default)
			)
			(fill no)
			(layer "F.CrtYd")
		)
		(fp_rect
			(start -0.5842 1.3335)
			(end 0.5842 -1.3335)
			(stroke
				(width 0)
				(type default)
			)
			(fill no)
			(layer "F.Fab")
		)
		(pad "1" smd custom
			(at 0 -0.762)
			(size 0.2159 0.2159)
			(layers "F.Cu" "F.Mask" "F.Paste")
			(net "I2C_C_BUF_SCL_CONN")
			(options
				(clearance outline)
				(anchor circle)
			)
			(primitives
				(gr_poly
					(pts
						(arc
							(start -0.3302 -0.4318)
							(mid -0.402042 -0.402042)
							(end -0.4318 -0.3302)
						)
						(arc
							(start -0.4318 0.3302)
							(mid -0.402042 0.402042)
							(end -0.3302 0.4318)
						)
						(arc
							(start 0.3302 0.4318)
							(mid 0.402042 0.402042)
							(end 0.4318 0.3302)
						)
						(arc
							(start 0.4318 -0.3302)
							(mid 0.402042 -0.402042)
							(end 0.3302 -0.4318)
						)
					)
					(width 0)
					(fill yes)
				)
			)
		)
		(pad "2" smd custom
			(at 0 0.762)
			(size 0.2159 0.2159)
			(layers "F.Cu" "F.Mask" "F.Paste")
			(net "GND")
			(options
				(clearance outline)
				(anchor circle)
			)
			(primitives
				(gr_poly
					(pts
						(arc
							(start -0.3302 -0.4318)
							(mid -0.402042 -0.402042)
							(end -0.4318 -0.3302)
						)
						(arc
							(start -0.4318 0.3302)
							(mid -0.402042 0.402042)
							(end -0.3302 0.4318)
						)
						(arc
							(start 0.3302 0.4318)
							(mid 0.402042 0.402042)
							(end 0.4318 0.3302)
						)
						(arc
							(start 0.4318 -0.3302)
							(mid 0.402042 -0.402042)
							(end 0.3302 -0.4318)
						)
					)
					(width 0)
					(fill yes)
				)
			)
		)
	)
	(footprint ""
		(layer "F.Cu")
		(at 13.650468 -94.361508)
		(property "Reference" "U51"
			(at 0 0 0)
			(layer "F.SilkS")
			(hide yes)
			(effects
				(font
					(size 1.27 1.27)
				)
			)
		)
		(property "Value" "PCA9511ADP-T-GP"
			(at 0 -13.1572 0)
			(unlocked yes)
			(layer "F.Fab")
			(hide yes)
			(effects
				(font
					(size 1.016 1.016)
					(thickness 0.1524)
				)
			)
		)
		(property "Device Type" "SSOIC8-2H44"
			(at 0 -15.1892 0)
			(unlocked yes)
			(layer "F.Fab")
			(hide yes)
			(effects
				(font
					(size 1.016 1.016)
					(thickness 0.1524)
				)
			)
		)
		(duplicate_pad_numbers_are_jumpers no)
		(fp_line
			(start -1.9304 -1.016)
			(end 1.0922 -1.016)
			(stroke
				(width 0.1524)
				(type default)
			)
			(layer "F.SilkS")
		)
		(fp_line
			(start -1.9304 1.016)
			(end -1.9304 -1.016)
			(stroke
				(width 0.1524)
				(type default)
			)
			(layer "F.SilkS")
		)
		(fp_line
			(start -1.7018 1.0414)
			(end -1.7018 2.9718)
			(stroke
				(width 0.635)
				(type default)
			)
			(layer "F.SilkS")
		)
		(fp_line
			(start -1.524 0)
			(end -1.9304 -0.4064)
			(stroke
				(width 0.1524)
				(type default)
			)
			(layer "F.SilkS")
		)
		(fp_line
			(start -1.524 0)
			(end -1.9304 0.4064)
			(stroke
				(width 0.1524)
				(type default)
			)
			(layer "F.SilkS")
		)
		(fp_line
			(start 1.0922 -1.016)
			(end 1.0922 1.016)
			(stroke
				(width 0.1524)
				(type default)
			)
			(layer "F.SilkS")
		)
		(fp_line
			(start 1.0922 1.016)
			(end -1.9304 1.016)
			(stroke
				(width 0.1524)
				(type default)
			)
			(layer "F.SilkS")
		)
		(fp_poly
			(pts
				(xy -1.1938 -1.016) (xy 1.0922 -1.016) (xy 1.0922 1.016) (xy -1.1938 1.016)
			)
			(stroke
				(width 0)
				(type default)
			)
			(fill yes)
			(layer "F.SilkS")
		)
		(fp_rect
			(start -2.0066 3.3401)
			(end 2.0066 -3.3401)
			(stroke
				(width 0)
				(type default)
			)
			(fill no)
			(layer "F.CrtYd")
		)
		(fp_poly
			(pts
				(xy -2.0066 -3.3401) (xy 2.0066 -3.3401) (xy 2.0066 3.3401) (xy -2.0066 3.3401)
			)
			(stroke
				(width 0)
				(type default)
			)
			(fill no)
			(layer "F.Fab")
		)
		(pad "1" smd rect
			(at -0.97536 2.0701)
			(size 0.4064 1.524)
			(layers "F.Cu" "F.Mask" "F.Paste")
			(net "I2C_C_BUF_EN")
		)
		(pad "2" smd rect
			(at -0.32512 2.0701)
			(size 0.4064 1.524)
			(layers "F.Cu" "F.Mask" "F.Paste")
			(net "I2C_C_BUF_SCLOUT")
		)
		(pad "3" smd rect
			(at 0.32512 2.0701)
			(size 0.4064 1.524)
			(layers "F.Cu" "F.Mask" "F.Paste")
			(net "I2C_C_BUF_SCLIN")
		)
		(pad "4" smd rect
			(at 0.97536 2.0701)
			(size 0.4064 1.524)
			(layers "F.Cu" "F.Mask" "F.Paste")
			(net "GND")
		)
		(pad "5" smd rect
			(at 0.97536 -2.0701)
			(size 0.4064 1.524)
			(layers "F.Cu" "F.Mask" "F.Paste")
			(net "I2C_C_BUF_READY")
		)
		(pad "6" smd rect
			(at 0.32512 -2.0701)
			(size 0.4064 1.524)
			(layers "F.Cu" "F.Mask" "F.Paste")
			(net "I2C_C_BUF_SDAIN")
		)
		(pad "7" smd rect
			(at -0.32512 -2.0701)
			(size 0.4064 1.524)
			(layers "F.Cu" "F.Mask" "F.Paste")
			(net "I2C_C_BUF_SDAOUT")
		)
		(pad "8" smd rect
			(at -0.97536 -2.0701)
			(size 0.4064 1.524)
			(layers "F.Cu" "F.Mask" "F.Paste")
			(net "P3V3")
		)
	)
	(footprint ""
		(layer "F.Cu")
		(at -9.50087 -74.529188 -90)
		(property "Reference" "GF1"
			(at 0 0 270)
			(layer "F.SilkS")
			(hide yes)
			(effects
				(font
					(size 1.27 1.27)
				)
			)
		)
		(property "Value" "GF-36P-24P-GP"
			(at -19.5834 -9.482582 270)
			(unlocked yes)
			(layer "F.Fab")
			(hide yes)
			(effects
				(font
					(size 1.016 1.016)
					(thickness 0.1524)
				)
			)
		)
		(property "Device Type" "GF-36P-24P"
			(at -19.5834 -11.006582 270)
			(unlocked yes)
			(layer "F.Fab")
			(hide yes)
			(effects
				(font
					(size 1.016 1.016)
					(thickness 0.1524)
				)
			)
		)
		(duplicate_pad_numbers_are_jumpers no)
		(fp_rect
			(start -18.6436 2.032)
			(end 47.3964 -8.3312)
			(stroke
				(width 0)
				(type default)
			)
			(fill no)
			(layer "B.CrtYd")
		)
		(fp_rect
			(start -18.6436 2.032)
			(end 47.3964 -8.3312)
			(stroke
				(width 0)
				(type default)
			)
			(fill no)
			(layer "F.CrtYd")
		)
		(fp_rect
			(start -18.6436 2.032)
			(end 47.3964 -8.3312)
			(stroke
				(width 0)
				(type default)
			)
			(fill no)
			(layer "B.Fab")
		)
		(fp_rect
			(start -18.6436 2.032)
			(end 47.3964 -8.3312)
			(stroke
				(width 0)
				(type default)
			)
			(fill no)
			(layer "F.Fab")
		)
		(fp_text user "02 Do not mirror"
			(at 5.969 3.437636 270)
			(unlocked yes)
			(layer "F.Fab")
			(effects
				(font
					(size 1.016 1.016)
					(thickness 0.1524)
				)
				(justify left)
			)
		)
		(pad "P1" smd rect
			(at 40.64 -3.5306 270)
			(size 9.4488 6.2992)
			(drill
				(offset 0 0.381)
			)
			(layers "F.Cu" "F.Mask" "F.Paste")
			(net "P12V")
		)
		(pad "P2" smd rect
			(at 38.2778 -3.9116 270)
			(size 0.0254 0.0254)
			(layers "F.Cu" "F.Mask" "F.Paste")
			(net "P12V")
		)
		(pad "P3" smd rect
			(at 40.64 -3.9116 270)
			(size 0.0254 0.0254)
			(layers "F.Cu" "F.Mask" "F.Paste")
			(net "P12V")
		)
		(pad "P4" smd rect
			(at 43.0022 -3.9116 270)
			(size 0.0254 0.0254)
			(layers "F.Cu" "F.Mask" "F.Paste")
			(net "P12V")
		)
		(pad "P5" smd rect
			(at 30.48 -3.5306 270)
			(size 9.4488 6.2992)
			(drill
				(offset 0 0.381)
			)
			(layers "F.Cu" "F.Mask" "F.Paste")
			(net "P12V")
		)
		(pad "P6" smd rect
			(at 28.1178 -3.9116 270)
			(size 0.0254 0.0254)
			(layers "F.Cu" "F.Mask" "F.Paste")
			(net "P12V")
		)
		(pad "P7" smd rect
			(at 30.48 -3.9116 270)
			(size 0.0254 0.0254)
			(layers "F.Cu" "F.Mask" "F.Paste")
			(net "P12V")
		)
		(pad "P8" smd rect
			(at 32.8422 -3.9116 270)
			(size 0.0254 0.0254)
			(layers "F.Cu" "F.Mask" "F.Paste")
			(net "P12V")
		)
		(pad "P9" smd rect
			(at 20.32 -3.5306 270)
			(size 9.4488 6.2992)
			(drill
				(offset 0 0.381)
			)
			(layers "F.Cu" "F.Mask" "F.Paste")
			(net "GND")
		)
		(pad "P10" smd rect
			(at 17.9578 -3.9116 270)
			(size 0.0254 0.0254)
			(layers "F.Cu" "F.Mask" "F.Paste")
			(net "GND")
		)
		(pad "P11" smd rect
			(at 20.32 -3.9116 270)
			(size 0.0254 0.0254)
			(layers "F.Cu" "F.Mask" "F.Paste")
			(net "GND")
		)
		(pad "P12" smd rect
			(at 22.6822 -3.9116 270)
			(size 0.0254 0.0254)
			(layers "F.Cu" "F.Mask" "F.Paste")
			(net "GND")
		)
		(pad "P13" smd rect
			(at 10.16 -3.5306 270)
			(size 9.4488 6.2992)
			(drill
				(offset 0 0.381)
			)
			(layers "F.Cu" "F.Mask" "F.Paste")
			(net "GND")
		)
		(pad "P14" smd rect
			(at 7.7978 -3.9116 270)
			(size 0.0254 0.0254)
			(layers "F.Cu" "F.Mask" "F.Paste")
			(net "GND")
		)
		(pad "P15" smd rect
			(at 10.16 -3.9116 270)
			(size 0.0254 0.0254)
			(layers "F.Cu" "F.Mask" "F.Paste")
			(net "GND")
		)
		(pad "P16" smd rect
			(at 12.5222 -3.9116 270)
			(size 0.0254 0.0254)
			(layers "F.Cu" "F.Mask" "F.Paste")
			(net "GND")
		)
		(pad "P17" smd rect
			(at 2.6289 -3.5306 270)
			(size 4.191 6.2992)
			(drill
				(offset 0 0.381)
			)
			(layers "F.Cu" "F.Mask" "F.Paste")
			(net "GND")
		)
		(pad "P18" smd rect
			(at 2.6289 -3.9116 270)
			(size 0.0254 0.0254)
			(layers "F.Cu" "F.Mask" "F.Paste")
			(net "GND")
		)
		(pad "P19" smd rect
			(at 2.6289 -3.1496 270)
			(size 4.191 6.2992)
			(layers "F.Cu" "F.Mask" "F.Paste")
			(net "GND")
		)
		(pad "P20" smd rect
			(at 2.6289 -2.7686 270)
			(size 0.0254 0.0254)
			(layers "F.Cu" "F.Mask" "F.Paste")
			(net "GND")
		)
		(pad "P21" smd rect
			(at 10.16 -3.1496 270)
			(size 9.4488 6.2992)
			(layers "F.Cu" "F.Mask" "F.Paste")
			(net "GND")
		)
		(pad "P22" smd rect
			(at 7.7978 -2.7686 270)
			(size 0.0254 0.0254)
			(layers "F.Cu" "F.Mask" "F.Paste")
			(net "GND")
		)
		(pad "P23" smd rect
			(at 10.16 -2.7686 270)
			(size 0.0254 0.0254)
			(layers "F.Cu" "F.Mask" "F.Paste")
			(net "GND")
		)
		(pad "P24" smd rect
			(at 12.5222 -2.7686 270)
			(size 0.0254 0.0254)
			(layers "F.Cu" "F.Mask" "F.Paste")
			(net "GND")
		)
		(pad "P25" smd rect
			(at 20.32 -3.1496 270)
			(size 9.4488 6.2992)
			(layers "F.Cu" "F.Mask" "F.Paste")
			(net "GND")
		)
		(pad "P26" smd rect
			(at 17.9578 -2.7686 270)
			(size 0.0254 0.0254)
			(layers "F.Cu" "F.Mask" "F.Paste")
			(net "GND")
		)
		(pad "P27" smd rect
			(at 20.32 -2.7686 270)
			(size 0.0254 0.0254)
			(layers "F.Cu" "F.Mask" "F.Paste")
			(net "GND")
		)
		(pad "P28" smd rect
			(at 22.6822 -2.7686 270)
			(size 0.0254 0.0254)
			(layers "F.Cu" "F.Mask" "F.Paste")
			(net "GND")
		)
		(pad "P29" smd rect
			(at 30.48 -3.1496 270)
			(size 9.4488 6.2992)
			(layers "F.Cu" "F.Mask" "F.Paste")
			(net "P12V")
		)
		(pad "P30" smd rect
			(at 28.1178 -2.7686 270)
			(size 0.0254 0.0254)
			(layers "F.Cu" "F.Mask" "F.Paste")
			(net "P12V")
		)
		(pad "P31" smd rect
			(at 30.48 -2.7686 270)
			(size 0.0254 0.0254)
			(layers "F.Cu" "F.Mask" "F.Paste")
			(net "P12V")
		)
		(pad "P32" smd rect
			(at 32.8422 -2.7686 270)
			(size 0.0254 0.0254)
			(layers "F.Cu" "F.Mask" "F.Paste")
			(net "P12V")
		)
		(pad "P33" smd rect
			(at 40.64 -3.1496 270)
			(size 9.4488 6.2992)
			(layers "F.Cu" "F.Mask" "F.Paste")
			(net "P12V")
		)
		(pad "P34" smd rect
			(at 38.2778 -2.7686 270)
			(size 0.0254 0.0254)
			(layers "F.Cu" "F.Mask" "F.Paste")
			(net "P12V")
		)
		(pad "P35" smd rect
			(at 40.64 -2.7686 270)
			(size 0.0254 0.0254)
			(layers "F.Cu" "F.Mask" "F.Paste")
			(net "P12V")
		)
		(pad "P36" smd rect
			(at 43.0022 -2.7686 270)
			(size 0.0254 0.0254)
			(layers "F.Cu" "F.Mask" "F.Paste")
			(net "P12V")
		)
		(pad "S1" smd rect
			(at -2.23012 -2.8829 270)
			(size 0.8128 5.0038)
			(drill
				(offset 0 0.381)
			)
			(layers "F.Cu" "F.Mask" "F.Paste")
			(net "GND")
		)
		(pad "S2" smd rect
			(at -3.50012 -2.8829 270)
			(size 0.8128 5.0038)
			(drill
				(offset 0 0.381)
			)
			(layers "F.Cu" "F.Mask" "F.Paste")
			(net "P3V3")
		)
		(pad "S3" smd rect
			(at -4.77012 -2.8829 270)
			(size 0.8128 5.0038)
			(drill
				(offset 0 0.381)
			)
			(layers "F.Cu" "F.Mask" "F.Paste")
			(net "P3V3")
		)
		(pad "S4" smd rect
			(at -6.04012 -2.8829 270)
			(size 0.8128 5.0038)
			(drill
				(offset 0 0.381)
			)
			(layers "F.Cu" "F.Mask" "F.Paste")
			(net "PEER_TRAY_PRESENT")
		)
		(pad "S5" smd rect
			(at -7.31012 -2.8829 270)
			(size 0.8128 5.0038)
			(drill
				(offset 0 0.381)
			)
			(layers "F.Cu" "F.Mask" "F.Paste")
			(net "PWM_EXP_B")
		)
		(pad "S6" smd rect
			(at -8.58012 -2.8829 270)
			(size 0.8128 5.0038)
			(drill
				(offset 0 0.381)
			)
			(layers "F.Cu" "F.Mask" "F.Paste")
			(net "SELF_TRAY_PRESENT")
		)
		(pad "S7" smd rect
			(at -9.85012 -2.8829 270)
			(size 0.8128 5.0038)
			(drill
				(offset 0 0.381)
			)
			(layers "F.Cu" "F.Mask" "F.Paste")
			(net "PWM_EXP_A")
		)
		(pad "S8" smd rect
			(at -11.12012 -2.8829 270)
			(size 0.8128 5.0038)
			(drill
				(offset 0 0.381)
			)
			(layers "F.Cu" "F.Mask" "F.Paste")
			(net "GND")
		)
		(pad "S9" smd rect
			(at -12.39012 -2.8829 270)
			(size 0.8128 5.0038)
			(drill
				(offset 0 0.381)
			)
			(layers "F.Cu" "F.Mask" "F.Paste")
			(net "STRADDLE_I2C_C_SDA")
		)
		(pad "S10" smd rect
			(at -13.66012 -2.8829 270)
			(size 0.8128 5.0038)
			(drill
				(offset 0 0.381)
			)
			(layers "F.Cu" "F.Mask" "F.Paste")
			(net "GND")
		)
		(pad "S11" smd rect
			(at -14.93012 -2.8829 270)
			(size 0.8128 5.0038)
			(drill
				(offset 0 0.381)
			)
			(layers "F.Cu" "F.Mask" "F.Paste")
			(net "STRADDLE_I2C_C_SCL")
		)
		(pad "S12" smd rect
			(at -16.20012 -2.8829 270)
			(size 0.8128 5.0038)
			(drill
				(offset 0 0.381)
			)
			(layers "F.Cu" "F.Mask" "F.Paste")
			(net "GND")
		)
		(pad "S13" smd rect
			(at -16.20012 -2.5019 270)
			(size 0.8128 5.0038)
			(layers "F.Cu" "F.Mask" "F.Paste")
			(net "GND")
		)
		(pad "S14" smd rect
			(at -14.93012 -2.5019 270)
			(size 0.8128 5.0038)
			(layers "F.Cu" "F.Mask" "F.Paste")
			(net "SELF_1A&2A_HB")
		)
		(pad "S15" smd rect
			(at -13.66012 -2.5019 270)
			(size 0.8128 5.0038)
			(layers "F.Cu" "F.Mask" "F.Paste")
			(net "SELF_1B&2B_HB")
		)
		(pad "S16" smd rect
			(at -12.39012 -2.5019 270)
			(size 0.8128 5.0038)
			(layers "F.Cu" "F.Mask" "F.Paste")
			(net "TRAY_ID")
		)
		(pad "S17" smd rect
			(at -11.12012 -2.5019 270)
			(size 0.8128 5.0038)
			(layers "F.Cu" "F.Mask" "F.Paste")
			(net "FCB_HW_REV")
		)
		(pad "S18" smd rect
			(at -9.85012 -2.5019 270)
			(size 0.8128 5.0038)
			(layers "F.Cu" "F.Mask" "F.Paste")
			(net "SD_LATCH_RELEASE")
		)
		(pad "S19" smd rect
			(at -8.58012 -2.5019 270)
			(size 0.8128 5.0038)
			(layers "F.Cu" "F.Mask" "F.Paste")
			(net "GND")
		)
		(pad "S20" smd rect
			(at -7.31012 -2.5019 270)
			(size 0.8128 5.0038)
			(layers "F.Cu" "F.Mask" "F.Paste")
			(net "PEER_1A&2A_HB")
		)
		(pad "S21" smd rect
			(at -6.04012 -2.5019 270)
			(size 0.8128 5.0038)
			(layers "F.Cu" "F.Mask" "F.Paste")
			(net "PEER_1B&2B_HB")
		)
		(pad "S22" smd rect
			(at -4.77012 -2.5019 270)
			(size 0.8128 5.0038)
			(layers "F.Cu" "F.Mask" "F.Paste")
			(net "GND")
		)
		(pad "S23" smd rect
			(at -3.50012 -2.5019 270)
			(size 0.8128 5.0038)
			(layers "F.Cu" "F.Mask" "F.Paste")
			(net "GND")
		)
		(pad "S24" smd rect
			(at -2.23012 -2.5019 270)
			(size 0.8128 5.0038)
			(layers "F.Cu" "F.Mask" "F.Paste")
			(net "P5VA")
		)
		(zone
			(layer "F.Cu")
			(hatch none 0.5)
			(connect_pads
				(clearance 0)
			)
			(min_thickness 0.25)
			(keepout
				(tracks not_allowed)
				(vias allowed)
				(pads allowed)
				(copperpour not_allowed)
				(footprints allowed)
			)
			(placement
				(enabled no)
				(sheetname "")
			)
			(fill
				(thermal_gap 0.5)
				(thermal_bridge_width 0.5)
				(island_removal_mode 0)
			)
			(polygon
				(pts
					(xy -10.51687 -28.092908) (xy -9.50087 -28.092908) (xy -9.50087 -93.025468) (xy -10.51687 -93.025468)
				)
			)
		)
		(zone
			(layer "F.Cu")
			(hatch none 0.5)
			(connect_pads
				(clearance 0)
			)
			(min_thickness 0.25)
			(keepout
				(tracks allowed)
				(vias not_allowed)
				(pads allowed)
				(copperpour not_allowed)
				(footprints allowed)
			)
			(placement
				(enabled no)
				(sheetname "")
			)
			(fill
				(thermal_gap 0.5)
				(thermal_bridge_width 0.5)
				(island_removal_mode 0)
			)
			(polygon
				(pts
					(xy -10.51687 -28.092908) (xy -2.18567 -28.092908) (xy -2.18567 -93.025468) (xy -10.51687 -93.025468)
				)
			)
		)
		(zone
			(layer "B.Cu")
			(hatch none 0.5)
			(connect_pads
				(clearance 0)
			)
			(min_thickness 0.25)
			(keepout
				(tracks not_allowed)
				(vias allowed)
				(pads allowed)
				(copperpour not_allowed)
				(footprints allowed)
			)
			(placement
				(enabled no)
				(sheetname "")
			)
			(fill
				(thermal_gap 0.5)
				(thermal_bridge_width 0.5)
				(island_removal_mode 0)
			)
			(polygon
				(pts
					(xy -10.51687 -28.092908) (xy -9.50087 -28.092908) (xy -9.50087 -93.025468) (xy -10.51687 -93.025468)
				)
			)
		)
		(zone
			(layer "B.Cu")
			(hatch none 0.5)
			(connect_pads
				(clearance 0)
			)
			(min_thickness 0.25)
			(keepout
				(tracks allowed)
				(vias not_allowed)
				(pads allowed)
				(copperpour not_allowed)
				(footprints allowed)
			)
			(placement
				(enabled no)
				(sheetname "")
			)
			(fill
				(thermal_gap 0.5)
				(thermal_bridge_width 0.5)
				(island_removal_mode 0)
			)
			(polygon
				(pts
					(xy -10.51687 -28.092908) (xy -2.18567 -28.092908) (xy -2.18567 -93.025468) (xy -10.51687 -93.025468)
				)
			)
		)
	)
	(footprint ""
		(layer "F.Cu")
		(at 139.192 -109.474)
		(property "Reference" "R391"
			(at 0 0 0)
			(layer "F.SilkS")
			(hide yes)
			(effects
				(font
					(size 1.27 1.27)
				)
			)
		)
		(property "Value" "0R2J-2-GP"
			(at 0.064008 -3.993896 0)
			(unlocked yes)
			(layer "F.Fab")
			(hide yes)
			(effects
				(font
					(size 1.016 1.016)
					(thickness 0.1524)
				)
			)
		)
		(property "Device Type" "R402H16"
			(at 0.064008 -5.517896 0)
			(unlocked yes)
			(layer "F.Fab")
			(hide yes)
			(effects
				(font
					(size 1.016 1.016)
					(thickness 0.1524)
				)
			)
		)
		(duplicate_pad_numbers_are_jumpers no)
		(fp_line
			(start -0.508 -0.9398)
			(end -0.508 0.9398)
			(stroke
				(width 0.1524)
				(type default)
			)
			(layer "F.SilkS")
		)
		(fp_line
			(start 0.508 -0.9398)
			(end -0.508 -0.9398)
			(stroke
				(width 0.1524)
				(type default)
			)
			(layer "F.SilkS")
		)
		(fp_rect
			(start -0.508 0.9398)
			(end 0.508 -0.9398)
			(stroke
				(width 0)
				(type default)
			)
			(fill no)
			(layer "F.CrtYd")
		)
		(fp_rect
			(start -0.508 0.9398)
			(end 0.508 -0.9398)
			(stroke
				(width 0)
				(type default)
			)
			(fill no)
			(layer "F.Fab")
		)
		(pad "1" smd custom
			(at 0 -0.4445)
			(size 0.1397 0.1397)
			(layers "F.Cu" "F.Mask" "F.Paste")
			(net "TPS2490_EN1")
			(options
				(clearance outline)
				(anchor circle)
			)
			(primitives
				(gr_poly
					(pts
						(arc
							(start -0.1778 -0.2794)
							(mid -0.249642 -0.249642)
							(end -0.2794 -0.1778)
						)
						(arc
							(start -0.2794 0.1778)
							(mid -0.249642 0.249642)
							(end -0.1778 0.2794)
						)
						(arc
							(start 0.1778 0.2794)
							(mid 0.249642 0.249642)
							(end 0.2794 0.1778)
						)
						(arc
							(start 0.2794 -0.1778)
							(mid 0.249642 -0.249642)
							(end 0.1778 -0.2794)
						)
					)
					(width 0)
					(fill yes)
				)
			)
		)
		(pad "2" smd custom
			(at 0 0.4445)
			(size 0.1397 0.1397)
			(layers "F.Cu" "F.Mask" "F.Paste")
			(net "TPS2490_EN2")
			(options
				(clearance outline)
				(anchor circle)
			)
			(primitives
				(gr_poly
					(pts
						(arc
							(start -0.1778 -0.2794)
							(mid -0.249642 -0.249642)
							(end -0.2794 -0.1778)
						)
						(arc
							(start -0.2794 0.1778)
							(mid -0.249642 0.249642)
							(end -0.1778 0.2794)
						)
						(arc
							(start 0.1778 0.2794)
							(mid 0.249642 0.249642)
							(end 0.2794 0.1778)
						)
						(arc
							(start 0.2794 -0.1778)
							(mid 0.249642 -0.249642)
							(end 0.1778 -0.2794)
						)
					)
					(width 0)
					(fill yes)
				)
			)
		)
	)
	(footprint ""
		(layer "F.Cu")
		(at 14.059408 -98.824796)
		(property "Reference" "R370"
			(at 0 0 0)
			(layer "F.SilkS")
			(hide yes)
			(effects
				(font
					(size 1.27 1.27)
				)
			)
		)
		(property "Value" "4K7R2J-2-GP"
			(at 0.064008 -3.993896 0)
			(unlocked yes)
			(layer "F.Fab")
			(hide yes)
			(effects
				(font
					(size 1.016 1.016)
					(thickness 0.1524)
				)
			)
		)
		(property "Device Type" "R402H16"
			(at 0.064008 -5.517896 0)
			(unlocked yes)
			(layer "F.Fab")
			(hide yes)
			(effects
				(font
					(size 1.016 1.016)
					(thickness 0.1524)
				)
			)
		)
		(duplicate_pad_numbers_are_jumpers no)
		(fp_line
			(start -0.508 -0.9398)
			(end -0.508 0.9398)
			(stroke
				(width 0.1524)
				(type default)
			)
			(layer "F.SilkS")
		)
		(fp_line
			(start 0.508 -0.9398)
			(end -0.508 -0.9398)
			(stroke
				(width 0.1524)
				(type default)
			)
			(layer "F.SilkS")
		)
		(fp_rect
			(start -0.508 0.9398)
			(end 0.508 -0.9398)
			(stroke
				(width 0)
				(type default)
			)
			(fill no)
			(layer "F.CrtYd")
		)
		(fp_rect
			(start -0.508 0.9398)
			(end 0.508 -0.9398)
			(stroke
				(width 0)
				(type default)
			)
			(fill no)
			(layer "F.Fab")
		)
		(pad "1" smd custom
			(at 0 -0.4445)
			(size 0.1397 0.1397)
			(layers "F.Cu" "F.Mask" "F.Paste")
			(net "P3V3")
			(options
				(clearance outline)
				(anchor circle)
			)
			(primitives
				(gr_poly
					(pts
						(arc
							(start -0.1778 -0.2794)
							(mid -0.249642 -0.249642)
							(end -0.2794 -0.1778)
						)
						(arc
							(start -0.2794 0.1778)
							(mid -0.249642 0.249642)
							(end -0.1778 0.2794)
						)
						(arc
							(start 0.1778 0.2794)
							(mid 0.249642 0.249642)
							(end 0.2794 0.1778)
						)
						(arc
							(start 0.2794 -0.1778)
							(mid 0.249642 -0.249642)
							(end 0.1778 -0.2794)
						)
					)
					(width 0)
					(fill yes)
				)
			)
		)
		(pad "2" smd custom
			(at 0 0.4445)
			(size 0.1397 0.1397)
			(layers "F.Cu" "F.Mask" "F.Paste")
			(net "I2C_C_BUF_SDAIN")
			(options
				(clearance outline)
				(anchor circle)
			)
			(primitives
				(gr_poly
					(pts
						(arc
							(start -0.1778 -0.2794)
							(mid -0.249642 -0.249642)
							(end -0.2794 -0.1778)
						)
						(arc
							(start -0.2794 0.1778)
							(mid -0.249642 0.249642)
							(end -0.1778 0.2794)
						)
						(arc
							(start 0.1778 0.2794)
							(mid 0.249642 0.249642)
							(end 0.2794 0.1778)
						)
						(arc
							(start 0.2794 -0.1778)
							(mid 0.249642 -0.249642)
							(end 0.1778 -0.2794)
						)
					)
					(width 0)
					(fill yes)
				)
			)
		)
	)
	(footprint ""
		(layer "F.Cu")
		(at 8.079232 -95.029528 90)
		(property "Reference" "R388"
			(at 0 0 90)
			(layer "F.SilkS")
			(hide yes)
			(effects
				(font
					(size 1.27 1.27)
				)
			)
		)
		(property "Value" "0R2J-2-GP"
			(at 0.064008 -3.993896 90)
			(unlocked yes)
			(layer "F.Fab")
			(hide yes)
			(effects
				(font
					(size 1.016 1.016)
					(thickness 0.1524)
				)
			)
		)
		(property "Device Type" "R402H16"
			(at 0.064008 -5.517896 90)
			(unlocked yes)
			(layer "F.Fab")
			(hide yes)
			(effects
				(font
					(size 1.016 1.016)
					(thickness 0.1524)
				)
			)
		)
		(duplicate_pad_numbers_are_jumpers no)
		(fp_line
			(start 0.508 -0.9398)
			(end -0.508 -0.9398)
			(stroke
				(width 0.1524)
				(type default)
			)
			(layer "F.SilkS")
		)
		(fp_line
			(start -0.508 -0.9398)
			(end -0.508 0.9398)
			(stroke
				(width 0.1524)
				(type default)
			)
			(layer "F.SilkS")
		)
		(fp_rect
			(start -0.508 0.9398)
			(end 0.508 -0.9398)
			(stroke
				(width 0)
				(type default)
			)
			(fill no)
			(layer "F.CrtYd")
		)
		(fp_rect
			(start -0.508 0.9398)
			(end 0.508 -0.9398)
			(stroke
				(width 0)
				(type default)
			)
			(fill no)
			(layer "F.Fab")
		)
		(pad "1" smd custom
			(at 0 -0.4445 90)
			(size 0.1397 0.1397)
			(layers "F.Cu" "F.Mask" "F.Paste")
			(net "STRADDLE_I2C_C_SDA")
			(options
				(clearance outline)
				(anchor circle)
			)
			(primitives
				(gr_poly
					(pts
						(arc
							(start -0.1778 -0.2794)
							(mid -0.249642 -0.249642)
							(end -0.2794 -0.1778)
						)
						(arc
							(start -0.2794 0.1778)
							(mid -0.249642 0.249642)
							(end -0.1778 0.2794)
						)
						(arc
							(start 0.1778 0.2794)
							(mid 0.249642 0.249642)
							(end 0.2794 0.1778)
						)
						(arc
							(start 0.2794 -0.1778)
							(mid 0.249642 -0.249642)
							(end 0.1778 -0.2794)
						)
					)
					(width 0)
					(fill yes)
				)
			)
		)
		(pad "2" smd custom
			(at 0 0.4445 90)
			(size 0.1397 0.1397)
			(layers "F.Cu" "F.Mask" "F.Paste")
			(net "I2C_C_SDA")
			(options
				(clearance outline)
				(anchor circle)
			)
			(primitives
				(gr_poly
					(pts
						(arc
							(start -0.1778 -0.2794)
							(mid -0.249642 -0.249642)
							(end -0.2794 -0.1778)
						)
						(arc
							(start -0.2794 0.1778)
							(mid -0.249642 0.249642)
							(end -0.1778 0.2794)
						)
						(arc
							(start 0.1778 0.2794)
							(mid 0.249642 0.249642)
							(end 0.2794 0.1778)
						)
						(arc
							(start 0.2794 -0.1778)
							(mid 0.249642 -0.249642)
							(end 0.1778 -0.2794)
						)
					)
					(width 0)
					(fill yes)
				)
			)
		)
	)
	(footprint ""
		(layer "F.Cu")
		(at 14.579092 -89.95664 180)
		(property "Reference" "R369"
			(at 0 0 180)
			(layer "F.SilkS")
			(hide yes)
			(effects
				(font
					(size 1.27 1.27)
				)
			)
		)
		(property "Value" "4K7R2J-2-GP"
			(at 0.064008 -3.993896 180)
			(unlocked yes)
			(layer "F.Fab")
			(hide yes)
			(effects
				(font
					(size 1.016 1.016)
					(thickness 0.1524)
				)
			)
		)
		(property "Device Type" "R402H16"
			(at 0.064008 -5.517896 180)
			(unlocked yes)
			(layer "F.Fab")
			(hide yes)
			(effects
				(font
					(size 1.016 1.016)
					(thickness 0.1524)
				)
			)
		)
		(duplicate_pad_numbers_are_jumpers no)
		(fp_line
			(start 0.508 -0.9398)
			(end -0.508 -0.9398)
			(stroke
				(width 0.1524)
				(type default)
			)
			(layer "F.SilkS")
		)
		(fp_line
			(start -0.508 -0.9398)
			(end -0.508 0.9398)
			(stroke
				(width 0.1524)
				(type default)
			)
			(layer "F.SilkS")
		)
		(fp_rect
			(start -0.508 0.9398)
			(end 0.508 -0.9398)
			(stroke
				(width 0)
				(type default)
			)
			(fill no)
			(layer "F.CrtYd")
		)
		(fp_rect
			(start -0.508 0.9398)
			(end 0.508 -0.9398)
			(stroke
				(width 0)
				(type default)
			)
			(fill no)
			(layer "F.Fab")
		)
		(pad "1" smd custom
			(at 0 -0.4445 180)
			(size 0.1397 0.1397)
			(layers "F.Cu" "F.Mask" "F.Paste")
			(net "P3V3")
			(options
				(clearance outline)
				(anchor circle)
			)
			(primitives
				(gr_poly
					(pts
						(arc
							(start -0.1778 -0.2794)
							(mid -0.249642 -0.249642)
							(end -0.2794 -0.1778)
						)
						(arc
							(start -0.2794 0.1778)
							(mid -0.249642 0.249642)
							(end -0.1778 0.2794)
						)
						(arc
							(start 0.1778 0.2794)
							(mid 0.249642 0.249642)
							(end 0.2794 0.1778)
						)
						(arc
							(start 0.2794 -0.1778)
							(mid 0.249642 -0.249642)
							(end 0.1778 -0.2794)
						)
					)
					(width 0)
					(fill yes)
				)
			)
		)
		(pad "2" smd custom
			(at 0 0.4445 180)
			(size 0.1397 0.1397)
			(layers "F.Cu" "F.Mask" "F.Paste")
			(net "I2C_C_BUF_SCLIN")
			(options
				(clearance outline)
				(anchor circle)
			)
			(primitives
				(gr_poly
					(pts
						(arc
							(start -0.1778 -0.2794)
							(mid -0.249642 -0.249642)
							(end -0.2794 -0.1778)
						)
						(arc
							(start -0.2794 0.1778)
							(mid -0.249642 0.249642)
							(end -0.1778 0.2794)
						)
						(arc
							(start 0.1778 0.2794)
							(mid 0.249642 0.249642)
							(end 0.2794 0.1778)
						)
						(arc
							(start 0.2794 -0.1778)
							(mid 0.249642 -0.249642)
							(end 0.1778 -0.2794)
						)
					)
					(width 0)
					(fill yes)
				)
			)
		)
	)
	(footprint ""
		(layer "F.Cu")
		(at 15.253208 -98.803968)
		(property "Reference" "R353"
			(at 0 0 0)
			(layer "F.SilkS")
			(hide yes)
			(effects
				(font
					(size 1.27 1.27)
				)
			)
		)
		(property "Value" "10KR2F-2-GP"
			(at 0.064008 -3.993896 0)
			(unlocked yes)
			(layer "F.Fab")
			(hide yes)
			(effects
				(font
					(size 1.016 1.016)
					(thickness 0.1524)
				)
			)
		)
		(property "Device Type" "R402H16"
			(at 0.064008 -5.517896 0)
			(unlocked yes)
			(layer "F.Fab")
			(hide yes)
			(effects
				(font
					(size 1.016 1.016)
					(thickness 0.1524)
				)
			)
		)
		(duplicate_pad_numbers_are_jumpers no)
		(fp_line
			(start -0.508 -0.9398)
			(end -0.508 0.9398)
			(stroke
				(width 0.1524)
				(type default)
			)
			(layer "F.SilkS")
		)
		(fp_line
			(start 0.508 -0.9398)
			(end -0.508 -0.9398)
			(stroke
				(width 0.1524)
				(type default)
			)
			(layer "F.SilkS")
		)
		(fp_rect
			(start -0.508 0.9398)
			(end 0.508 -0.9398)
			(stroke
				(width 0)
				(type default)
			)
			(fill no)
			(layer "F.CrtYd")
		)
		(fp_rect
			(start -0.508 0.9398)
			(end 0.508 -0.9398)
			(stroke
				(width 0)
				(type default)
			)
			(fill no)
			(layer "F.Fab")
		)
		(pad "1" smd custom
			(at 0 -0.4445)
			(size 0.1397 0.1397)
			(layers "F.Cu" "F.Mask" "F.Paste")
			(net "P3V3")
			(options
				(clearance outline)
				(anchor circle)
			)
			(primitives
				(gr_poly
					(pts
						(arc
							(start -0.1778 -0.2794)
							(mid -0.249642 -0.249642)
							(end -0.2794 -0.1778)
						)
						(arc
							(start -0.2794 0.1778)
							(mid -0.249642 0.249642)
							(end -0.1778 0.2794)
						)
						(arc
							(start 0.1778 0.2794)
							(mid 0.249642 0.249642)
							(end 0.2794 0.1778)
						)
						(arc
							(start 0.2794 -0.1778)
							(mid 0.249642 -0.249642)
							(end 0.1778 -0.2794)
						)
					)
					(width 0)
					(fill yes)
				)
			)
		)
		(pad "2" smd custom
			(at 0 0.4445)
			(size 0.1397 0.1397)
			(layers "F.Cu" "F.Mask" "F.Paste")
			(net "I2C_C_BUF_READY")
			(options
				(clearance outline)
				(anchor circle)
			)
			(primitives
				(gr_poly
					(pts
						(arc
							(start -0.1778 -0.2794)
							(mid -0.249642 -0.249642)
							(end -0.2794 -0.1778)
						)
						(arc
							(start -0.2794 0.1778)
							(mid -0.249642 0.249642)
							(end -0.1778 0.2794)
						)
						(arc
							(start 0.1778 0.2794)
							(mid 0.249642 0.249642)
							(end 0.2794 0.1778)
						)
						(arc
							(start 0.2794 -0.1778)
							(mid 0.249642 -0.249642)
							(end 0.1778 -0.2794)
						)
					)
					(width 0)
					(fill yes)
				)
			)
		)
	)
	(footprint ""
		(layer "F.Cu")
		(at 9.372092 -84.692744 90)
		(property "Reference" "R384"
			(at 0 0 90)
			(layer "F.SilkS")
			(hide yes)
			(effects
				(font
					(size 1.27 1.27)
				)
			)
		)
		(property "Value" "0R2J-2-GP"
			(at 0.064008 -3.993896 90)
			(unlocked yes)
			(layer "F.Fab")
			(hide yes)
			(effects
				(font
					(size 1.016 1.016)
					(thickness 0.1524)
				)
			)
		)
		(property "Device Type" "R402H16"
			(at 0.064008 -5.517896 90)
			(unlocked yes)
			(layer "F.Fab")
			(hide yes)
			(effects
				(font
					(size 1.016 1.016)
					(thickness 0.1524)
				)
			)
		)
		(duplicate_pad_numbers_are_jumpers no)
		(fp_line
			(start 0.508 -0.9398)
			(end -0.508 -0.9398)
			(stroke
				(width 0.1524)
				(type default)
			)
			(layer "F.SilkS")
		)
		(fp_line
			(start -0.508 -0.9398)
			(end -0.508 0.9398)
			(stroke
				(width 0.1524)
				(type default)
			)
			(layer "F.SilkS")
		)
		(fp_rect
			(start -0.508 0.9398)
			(end 0.508 -0.9398)
			(stroke
				(width 0)
				(type default)
			)
			(fill no)
			(layer "F.CrtYd")
		)
		(fp_rect
			(start -0.508 0.9398)
			(end 0.508 -0.9398)
			(stroke
				(width 0)
				(type default)
			)
			(fill no)
			(layer "F.Fab")
		)
		(pad "1" smd custom
			(at 0 -0.4445 90)
			(size 0.1397 0.1397)
			(layers "F.Cu" "F.Mask" "F.Paste")
			(net "PWM_EXP_A")
			(options
				(clearance outline)
				(anchor circle)
			)
			(primitives
				(gr_poly
					(pts
						(arc
							(start -0.1778 -0.2794)
							(mid -0.249642 -0.249642)
							(end -0.2794 -0.1778)
						)
						(arc
							(start -0.2794 0.1778)
							(mid -0.249642 0.249642)
							(end -0.1778 0.2794)
						)
						(arc
							(start 0.1778 0.2794)
							(mid 0.249642 0.249642)
							(end 0.2794 0.1778)
						)
						(arc
							(start 0.2794 -0.1778)
							(mid 0.249642 -0.249642)
							(end 0.1778 -0.2794)
						)
					)
					(width 0)
					(fill yes)
				)
			)
		)
		(pad "2" smd custom
			(at 0 0.4445 90)
			(size 0.1397 0.1397)
			(layers "F.Cu" "F.Mask" "F.Paste")
			(net "PWM_EXP_A_OUT")
			(options
				(clearance outline)
				(anchor circle)
			)
			(primitives
				(gr_poly
					(pts
						(arc
							(start -0.1778 -0.2794)
							(mid -0.249642 -0.249642)
							(end -0.2794 -0.1778)
						)
						(arc
							(start -0.2794 0.1778)
							(mid -0.249642 0.249642)
							(end -0.1778 0.2794)
						)
						(arc
							(start 0.1778 0.2794)
							(mid 0.249642 0.249642)
							(end 0.2794 0.1778)
						)
						(arc
							(start 0.2794 -0.1778)
							(mid 0.249642 -0.249642)
							(end 0.1778 -0.2794)
						)
					)
					(width 0)
					(fill yes)
				)
			)
		)
	)
	(footprint ""
		(layer "F.Cu")
		(at 17.121632 -99.379786)
		(property "Reference" "TP9"
			(at 0 0 0)
			(layer "F.SilkS")
			(hide yes)
			(effects
				(font
					(size 1.27 1.27)
				)
			)
		)
		(property "Value" "TPAD32-GP"
			(at 0 -3.166364 0)
			(unlocked yes)
			(layer "F.Fab")
			(hide yes)
			(effects
				(font
					(size 1.016 1.016)
					(thickness 0.1524)
				)
			)
		)
		(property "Device Type" "TPAD32"
			(at 0 -4.690618 0)
			(unlocked yes)
			(layer "F.Fab")
			(hide yes)
			(effects
				(font
					(size 1.016 1.016)
					(thickness 0.1524)
				)
			)
		)
		(duplicate_pad_numbers_are_jumpers no)
		(fp_poly
			(pts
				(arc
					(start 0.4064 0)
					(mid -0.4064 0)
					(end 0.4064 0)
				)
			)
			(stroke
				(width 0)
				(type default)
			)
			(fill no)
			(layer "F.CrtYd")
		)
		(fp_poly
			(pts
				(arc
					(start 0.7112 0)
					(mid -0.7112 0)
					(end 0.7112 0)
				)
			)
			(stroke
				(width 0)
				(type default)
			)
			(fill no)
			(layer "F.Fab")
		)
		(pad "1" smd circle
			(at 0 0)
			(size 0.8128 0.8128)
			(layers "F.Cu" "F.Mask" "F.Paste")
			(net "I2C_C_BUF_READY")
		)
	)
	(footprint ""
		(layer "F.Cu")
		(at 136.68629 -47.187358 180)
		(property "Reference" "TC4"
			(at 0 0 180)
			(layer "F.SilkS")
			(hide yes)
			(effects
				(font
					(size 1.27 1.27)
				)
			)
		)
		(property "Value" "ST68U16VDM-1-GP"
			(at 0 -9.6012 180)
			(unlocked yes)
			(layer "F.Fab")
			(hide yes)
			(effects
				(font
					(size 1.016 1.016)
					(thickness 0.1524)
				)
			)
		)
		(property "Device Type" "CT7343H79"
			(at 0 -11.1252 180)
			(unlocked yes)
			(layer "F.Fab")
			(hide yes)
			(effects
				(font
					(size 1.016 1.016)
					(thickness 0.1524)
				)
			)
		)
		(duplicate_pad_numbers_are_jumpers no)
		(fp_line
			(start 2.286 4.8768)
			(end -2.286 4.8768)
			(stroke
				(width 0.1524)
				(type default)
			)
			(layer "F.SilkS")
		)
		(fp_line
			(start 2.286 2.032)
			(end 2.286 4.8768)
			(stroke
				(width 0.1524)
				(type default)
			)
			(layer "F.SilkS")
		)
		(fp_line
			(start 2.286 -2.032)
			(end 2.286 -4.8768)
			(stroke
				(width 0.1524)
				(type default)
			)
			(layer "F.SilkS")
		)
		(fp_line
			(start 2.286 -4.8768)
			(end -2.286 -4.8768)
			(stroke
				(width 0.1524)
				(type default)
			)
			(layer "F.SilkS")
		)
		(fp_line
			(start 2.1082 -4.699)
			(end -2.1082 -4.699)
			(stroke
				(width 0.508)
				(type default)
			)
			(layer "F.SilkS")
		)
		(fp_line
			(start -2.286 4.8768)
			(end -2.286 2.032)
			(stroke
				(width 0.1524)
				(type default)
			)
			(layer "F.SilkS")
		)
		(fp_line
			(start -2.286 -4.8768)
			(end -2.286 -2.032)
			(stroke
				(width 0.1524)
				(type default)
			)
			(layer "F.SilkS")
		)
		(fp_rect
			(start -2.1463 3.6449)
			(end 2.1463 -3.6449)
			(stroke
				(width 0)
				(type default)
			)
			(fill no)
			(layer "F.CrtYd")
		)
		(fp_poly
			(pts
				(xy -2.54 4.953) (xy -2.54 4.2926) (xy -3.81 4.2926) (xy -3.81 -4.2926) (xy -2.54 -4.2926) (xy -2.54 -4.953)
				(xy 2.54 -4.953) (xy 2.54 -4.2926) (xy 3.81 -4.2926) (xy 3.81 -1.6256) (xy 2.1463 -1.6256) (xy 2.1463 -3.6449)
				(xy -2.1463 -3.6449) (xy -2.1463 3.6449) (xy 2.1463 3.6449) (xy 2.1463 -1.6129) (xy 3.81 -1.6129)
				(xy 3.81 4.2926) (xy 2.54 4.2926) (xy 2.54 4.953)
			)
			(stroke
				(width 0)
				(type default)
			)
			(fill no)
			(layer "F.CrtYd")
		)
		(fp_rect
			(start 2.54 4.2926)
			(end 3.81 -4.2926)
			(stroke
				(width 0)
				(type default)
			)
			(fill no)
			(layer "F.Fab")
		)
		(fp_rect
			(start -2.54 4.953)
			(end 2.54 -4.953)
			(stroke
				(width 0)
				(type default)
			)
			(fill no)
			(layer "F.Fab")
		)
		(fp_rect
			(start -3.81 4.2926)
			(end -2.54 -4.2926)
			(stroke
				(width 0)
				(type default)
			)
			(fill no)
			(layer "F.Fab")
		)
		(pad "1" smd rect
			(at 0 -3.1496 180)
			(size 2.413 2.286)
			(layers "F.Cu" "F.Mask" "F.Paste")
			(net "P12V")
		)
		(pad "2" smd rect
			(at 0 3.1496 180)
			(size 2.413 2.286)
			(layers "F.Cu" "F.Mask" "F.Paste")
			(net "GND")
		)
		(zone
			(layer "F.Cu")
			(hatch none 0.5)
			(connect_pads
				(clearance 0)
			)
			(min_thickness 0.25)
			(keepout
				(tracks allowed)
				(vias not_allowed)
				(pads allowed)
				(copperpour not_allowed)
				(footprints allowed)
			)
			(placement
				(enabled no)
				(sheetname "")
			)
			(fill
				(thermal_gap 0.5)
				(thermal_bridge_width 0.5)
				(island_removal_mode 0)
			)
			(polygon
				(pts
					(xy 135.17499 -45.498258) (xy 135.17499 -42.589958) (xy 138.19759 -42.589958) (xy 138.19759 -45.485558)
					(xy 138.19759 -45.815758) (xy 135.17499 -45.815758)
				)
			)
		)
		(zone
			(layer "F.Cu")
			(hatch none 0.5)
			(connect_pads
				(clearance 0)
			)
			(min_thickness 0.25)
			(keepout
				(tracks allowed)
				(vias not_allowed)
				(pads allowed)
				(copperpour not_allowed)
				(footprints allowed)
			)
			(placement
				(enabled no)
				(sheetname "")
			)
			(fill
				(thermal_gap 0.5)
				(thermal_bridge_width 0.5)
				(island_removal_mode 0)
			)
			(polygon
				(pts
					(xy 138.19759 -51.784758) (xy 135.17499 -51.784758) (xy 135.17499 -48.889158) (xy 135.17499 -48.558958)
					(xy 138.19759 -48.558958) (xy 138.19759 -48.889158)
				)
			)
		)
	)
	(footprint ""
		(layer "F.Cu")
		(at 7.659878 -105.499916)
		(property "Reference" "H2"
			(at 0 0 0)
			(layer "F.SilkS")
			(hide yes)
			(effects
				(font
					(size 1.27 1.27)
				)
			)
		)
		(property "Value" "HOLE"
			(at -8.9789 -1.1176 0)
			(unlocked yes)
			(layer "F.Fab")
			(hide yes)
			(effects
				(font
					(size 1.016 1.016)
					(thickness 0.1524)
				)
			)
		)
		(property "Device Type" "HTE9B9R355-R-766"
			(at -8.9789 -2.6416 0)
			(unlocked yes)
			(layer "F.Fab")
			(hide yes)
			(effects
				(font
					(size 1.016 1.016)
					(thickness 0.1524)
				)
			)
		)
		(duplicate_pad_numbers_are_jumpers no)
		(fp_poly
			(pts
				(arc
					(start 4.8133 0)
					(mid -4.8133 0)
					(end 4.8133 0)
				)
			)
			(stroke
				(width 0)
				(type default)
			)
			(fill no)
			(layer "B.CrtYd")
		)
		(fp_poly
			(pts
				(arc
					(start 0 -4.8133)
					(mid 4.8133 0)
					(end 0 4.8133)
				)
				(xy -7.9629 4.8133) (xy -7.9629 -4.8133)
			)
			(stroke
				(width 0)
				(type default)
			)
			(fill no)
			(layer "F.CrtYd")
		)
		(fp_poly
			(pts
				(arc
					(start 4.8133 0)
					(mid -4.8133 0)
					(end 4.8133 0)
				)
			)
			(stroke
				(width 0)
				(type default)
			)
			(fill no)
			(layer "B.Fab")
		)
		(fp_poly
			(pts
				(arc
					(start 0 -4.8133)
					(mid 4.8133 0)
					(end 0 4.8133)
				)
				(xy -7.9629 4.8133) (xy -7.9629 -4.8133)
			)
			(stroke
				(width 0)
				(type default)
			)
			(fill no)
			(layer "F.Fab")
		)
		(pad "1" thru_hole custom
			(at 0 0)
			(size 2.25425 2.25425)
			(drill 3.556)
			(layers "*.Cu" "*.Mask")
			(remove_unused_layers no)
			(net "GND")
			(clearance -3.7973)
			(thermal_gap 0.3048)
			(options
				(clearance outline)
				(anchor circle)
			)
			(primitives
				(gr_poly
					(pts
						(arc
							(start 1.5748 -4.5085)
							(mid 6.0833 0)
							(end 1.5748 4.5085)
						)
						(xy -6.0833 4.5085) (xy -6.0833 -4.5085)
					)
					(width 0)
					(fill yes)
				)
			)
			(padstack
				(mode front_inner_back)
				(layer "Inner"
					(shape circle)
					(size 3.9624 3.9624)
					(clearance 0.3048)
				)
				(layer "B.Cu"
					(shape circle)
					(size 9.017 9.017)
					(clearance -2.2225)
				)
			)
		)
	)
	(footprint ""
		(layer "F.Cu")
		(at 135.111744 -81.813908 90)
		(property "Reference" "R375"
			(at 0 0 90)
			(layer "F.SilkS")
			(hide yes)
			(effects
				(font
					(size 1.27 1.27)
				)
			)
		)
		(property "Value" "100R2F-L1-GP-U"
			(at 0.064008 -3.993896 90)
			(unlocked yes)
			(layer "F.Fab")
			(hide yes)
			(effects
				(font
					(size 1.016 1.016)
					(thickness 0.1524)
				)
			)
		)
		(property "Device Type" "R402H14"
			(at 0.064008 -5.517896 90)
			(unlocked yes)
			(layer "F.Fab")
			(hide yes)
			(effects
				(font
					(size 1.016 1.016)
					(thickness 0.1524)
				)
			)
		)
		(duplicate_pad_numbers_are_jumpers no)
		(fp_line
			(start 0.508 -0.9398)
			(end -0.508 -0.9398)
			(stroke
				(width 0.1524)
				(type default)
			)
			(layer "F.SilkS")
		)
		(fp_line
			(start -0.508 -0.9398)
			(end -0.508 0.9398)
			(stroke
				(width 0.1524)
				(type default)
			)
			(layer "F.SilkS")
		)
		(fp_rect
			(start -0.508 0.9398)
			(end 0.508 -0.9398)
			(stroke
				(width 0)
				(type default)
			)
			(fill no)
			(layer "F.CrtYd")
		)
		(fp_rect
			(start -0.508 0.9398)
			(end 0.508 -0.9398)
			(stroke
				(width 0)
				(type default)
			)
			(fill no)
			(layer "F.Fab")
		)
		(pad "1" smd custom
			(at 0 -0.4445 90)
			(size 0.1397 0.1397)
			(layers "F.Cu" "F.Mask" "F.Paste")
			(net "TRAY PRESENT_OUT_NET")
			(options
				(clearance outline)
				(anchor circle)
			)
			(primitives
				(gr_poly
					(pts
						(arc
							(start -0.1778 -0.2794)
							(mid -0.249642 -0.249642)
							(end -0.2794 -0.1778)
						)
						(arc
							(start -0.2794 0.1778)
							(mid -0.249642 0.249642)
							(end -0.1778 0.2794)
						)
						(arc
							(start 0.1778 0.2794)
							(mid 0.249642 0.249642)
							(end 0.2794 0.1778)
						)
						(arc
							(start 0.2794 -0.1778)
							(mid 0.249642 -0.249642)
							(end 0.1778 -0.2794)
						)
					)
					(width 0)
					(fill yes)
				)
			)
		)
		(pad "2" smd custom
			(at 0 0.4445 90)
			(size 0.1397 0.1397)
			(layers "F.Cu" "F.Mask" "F.Paste")
			(net "TRAY_PRESENT_OUT_NET_B")
			(options
				(clearance outline)
				(anchor circle)
			)
			(primitives
				(gr_poly
					(pts
						(arc
							(start -0.1778 -0.2794)
							(mid -0.249642 -0.249642)
							(end -0.2794 -0.1778)
						)
						(arc
							(start -0.2794 0.1778)
							(mid -0.249642 0.249642)
							(end -0.1778 0.2794)
						)
						(arc
							(start 0.1778 0.2794)
							(mid 0.249642 0.249642)
							(end 0.2794 0.1778)
						)
						(arc
							(start 0.2794 -0.1778)
							(mid 0.249642 -0.249642)
							(end 0.1778 -0.2794)
						)
					)
					(width 0)
					(fill yes)
				)
			)
		)
	)
	(footprint ""
		(layer "F.Cu")
		(at 117.348 -47.371 180)
		(property "Reference" "C361"
			(at 0 0 180)
			(layer "F.SilkS")
			(hide yes)
			(effects
				(font
					(size 1.27 1.27)
				)
			)
		)
		(property "Value" "SC47U16V0MX-GP"
			(at -0.00254 -4.78536 180)
			(unlocked yes)
			(layer "F.Fab")
			(hide yes)
			(effects
				(font
					(size 1.016 1.016)
					(thickness 0.1524)
				)
			)
		)
		(property "Device Type" "C1210H107"
			(at -0.00254 -6.38048 180)
			(unlocked yes)
			(layer "F.Fab")
			(hide yes)
			(effects
				(font
					(size 1.016 1.016)
					(thickness 0.1524)
				)
			)
		)
		(duplicate_pad_numbers_are_jumpers no)
		(fp_line
			(start 1.5748 2.3368)
			(end 1.5748 0.762)
			(stroke
				(width 0.1524)
				(type default)
			)
			(layer "F.SilkS")
		)
		(fp_line
			(start 1.5748 -0.762)
			(end 1.5748 -2.3368)
			(stroke
				(width 0.1524)
				(type default)
			)
			(layer "F.SilkS")
		)
		(fp_line
			(start 1.5748 -2.3368)
			(end -1.5748 -2.3368)
			(stroke
				(width 0.1524)
				(type default)
			)
			(layer "F.SilkS")
		)
		(fp_line
			(start -1.5748 2.3368)
			(end 1.5748 2.3368)
			(stroke
				(width 0.1524)
				(type default)
			)
			(layer "F.SilkS")
		)
		(fp_line
			(start -1.5748 0.762)
			(end -1.5748 2.3368)
			(stroke
				(width 0.1524)
				(type default)
			)
			(layer "F.SilkS")
		)
		(fp_line
			(start -1.5748 -2.3368)
			(end -1.5748 -0.762)
			(stroke
				(width 0.1524)
				(type default)
			)
			(layer "F.SilkS")
		)
		(fp_rect
			(start -1.651 2.413)
			(end 1.651 -2.413)
			(stroke
				(width 0)
				(type default)
			)
			(fill no)
			(layer "F.CrtYd")
		)
		(fp_poly
			(pts
				(xy 1.651 2.413) (xy 1.651 -2.413) (xy -1.651 -2.413) (xy -1.651 2.413)
			)
			(stroke
				(width 0)
				(type default)
			)
			(fill no)
			(layer "F.Fab")
		)
		(pad "1" smd rect
			(at 0 -1.4732 180)
			(size 2.794 1.397)
			(layers "F.Cu" "F.Mask" "F.Paste")
			(net "P12V")
		)
		(pad "2" smd rect
			(at 0 1.4732 180)
			(size 2.794 1.397)
			(layers "F.Cu" "F.Mask" "F.Paste")
			(net "GND")
		)
	)
	(footprint ""
		(layer "F.Cu")
		(at 131.659884 -113.999772)
		(property "Reference" "H1"
			(at 0 0 0)
			(layer "F.SilkS")
			(hide yes)
			(effects
				(font
					(size 1.27 1.27)
				)
			)
		)
		(property "Value" "HOLE"
			(at -18.200878 0.089916 0)
			(unlocked yes)
			(layer "F.Fab")
			(hide yes)
			(effects
				(font
					(size 1.016 1.016)
					(thickness 0.1524)
				)
			)
		)
		(property "Device Type" "HOLET827X355B355R158-S"
			(at -18.200878 -1.434084 0)
			(unlocked yes)
			(layer "F.Fab")
			(hide yes)
			(effects
				(font
					(size 1.016 1.016)
					(thickness 0.1524)
				)
			)
		)
		(duplicate_pad_numbers_are_jumpers no)
		(fp_poly
			(pts
				(arc
					(start 4.8133 0)
					(mid -4.8133 0)
					(end 4.8133 0)
				)
			)
			(stroke
				(width 0)
				(type default)
			)
			(fill no)
			(layer "B.CrtYd")
		)
		(fp_poly
			(pts
				(arc
					(start -11.9888 4.8133)
					(mid -16.8021 0)
					(end -11.9888 -4.8133)
				)
				(arc
					(start 0 -4.8133)
					(mid 4.8133 0)
					(end 0 4.8133)
				)
			)
			(stroke
				(width 0)
				(type default)
			)
			(fill no)
			(layer "F.CrtYd")
		)
		(fp_poly
			(pts
				(arc
					(start 4.8133 0)
					(mid -4.8133 0)
					(end 4.8133 0)
				)
			)
			(stroke
				(width 0)
				(type default)
			)
			(fill no)
			(layer "B.Fab")
		)
		(fp_poly
			(pts
				(arc
					(start -11.9888 4.8133)
					(mid -16.8021 0)
					(end -11.9888 -4.8133)
				)
				(arc
					(start 0 -4.8133)
					(mid 4.8133 0)
					(end 0 4.8133)
				)
			)
			(stroke
				(width 0)
				(type default)
			)
			(fill no)
			(layer "F.Fab")
		)
		(pad "1" thru_hole oval
			(at 0 0)
			(size 21.0058 9.017)
			(drill 4.0132
				(offset -5.9944 0)
			)
			(layers "*.Cu" "*.Mask")
			(remove_unused_layers no)
			(net "GND")
			(clearance -7.9883)
			(thermal_gap 0.3048)
			(padstack
				(mode front_inner_back)
				(layer "Inner"
					(shape circle)
					(size 4.4196 4.4196)
					(clearance 0.3048)
				)
				(layer "B.Cu"
					(shape circle)
					(size 9.017 9.017)
					(clearance -1.9939)
				)
			)
		)
	)
	(footprint ""
		(layer "F.Cu")
		(at 17.220692 -93.84538 90)
		(property "Reference" "R480"
			(at 0 0 90)
			(layer "F.SilkS")
			(hide yes)
			(effects
				(font
					(size 1.27 1.27)
				)
			)
		)
		(property "Value" "0R2J-2-GP"
			(at 0.064008 -3.993896 90)
			(unlocked yes)
			(layer "F.Fab")
			(hide yes)
			(effects
				(font
					(size 1.016 1.016)
					(thickness 0.1524)
				)
			)
		)
		(property "Device Type" "R402H16"
			(at 0.064008 -5.517896 90)
			(unlocked yes)
			(layer "F.Fab")
			(hide yes)
			(effects
				(font
					(size 1.016 1.016)
					(thickness 0.1524)
				)
			)
		)
		(duplicate_pad_numbers_are_jumpers no)
		(fp_line
			(start 0.508 -0.9398)
			(end -0.508 -0.9398)
			(stroke
				(width 0.1524)
				(type default)
			)
			(layer "F.SilkS")
		)
		(fp_line
			(start -0.508 -0.9398)
			(end -0.508 0.9398)
			(stroke
				(width 0.1524)
				(type default)
			)
			(layer "F.SilkS")
		)
		(fp_rect
			(start -0.508 0.9398)
			(end 0.508 -0.9398)
			(stroke
				(width 0)
				(type default)
			)
			(fill no)
			(layer "F.CrtYd")
		)
		(fp_rect
			(start -0.508 0.9398)
			(end 0.508 -0.9398)
			(stroke
				(width 0)
				(type default)
			)
			(fill no)
			(layer "F.Fab")
		)
		(pad "1" smd custom
			(at 0 -0.4445 90)
			(size 0.1397 0.1397)
			(layers "F.Cu" "F.Mask" "F.Paste")
			(net "I2C_C_SCL")
			(options
				(clearance outline)
				(anchor circle)
			)
			(primitives
				(gr_poly
					(pts
						(arc
							(start -0.1778 -0.2794)
							(mid -0.249642 -0.249642)
							(end -0.2794 -0.1778)
						)
						(arc
							(start -0.2794 0.1778)
							(mid -0.249642 0.249642)
							(end -0.1778 0.2794)
						)
						(arc
							(start 0.1778 0.2794)
							(mid 0.249642 0.249642)
							(end 0.2794 0.1778)
						)
						(arc
							(start 0.2794 -0.1778)
							(mid 0.249642 -0.249642)
							(end 0.1778 -0.2794)
						)
					)
					(width 0)
					(fill yes)
				)
			)
		)
		(pad "2" smd custom
			(at 0 0.4445 90)
			(size 0.1397 0.1397)
			(layers "F.Cu" "F.Mask" "F.Paste")
			(net "I2C_C_BUF_SCL")
			(options
				(clearance outline)
				(anchor circle)
			)
			(primitives
				(gr_poly
					(pts
						(arc
							(start -0.1778 -0.2794)
							(mid -0.249642 -0.249642)
							(end -0.2794 -0.1778)
						)
						(arc
							(start -0.2794 0.1778)
							(mid -0.249642 0.249642)
							(end -0.1778 0.2794)
						)
						(arc
							(start 0.1778 0.2794)
							(mid 0.249642 0.249642)
							(end 0.2794 0.1778)
						)
						(arc
							(start 0.2794 -0.1778)
							(mid 0.249642 -0.249642)
							(end 0.1778 -0.2794)
						)
					)
					(width 0)
					(fill yes)
				)
			)
		)
	)
	(footprint ""
		(layer "F.Cu")
		(at 136.652 -74.93)
		(property "Reference" "R379"
			(at 0 0 0)
			(layer "F.SilkS")
			(hide yes)
			(effects
				(font
					(size 1.27 1.27)
				)
			)
		)
		(property "Value" "10KR2F-2-GP"
			(at 0.064008 -3.993896 0)
			(unlocked yes)
			(layer "F.Fab")
			(hide yes)
			(effects
				(font
					(size 1.016 1.016)
					(thickness 0.1524)
				)
			)
		)
		(property "Device Type" "R402H16"
			(at 0.064008 -5.517896 0)
			(unlocked yes)
			(layer "F.Fab")
			(hide yes)
			(effects
				(font
					(size 1.016 1.016)
					(thickness 0.1524)
				)
			)
		)
		(duplicate_pad_numbers_are_jumpers no)
		(fp_line
			(start -0.508 -0.9398)
			(end -0.508 0.9398)
			(stroke
				(width 0.1524)
				(type default)
			)
			(layer "F.SilkS")
		)
		(fp_line
			(start 0.508 -0.9398)
			(end -0.508 -0.9398)
			(stroke
				(width 0.1524)
				(type default)
			)
			(layer "F.SilkS")
		)
		(fp_rect
			(start -0.508 0.9398)
			(end 0.508 -0.9398)
			(stroke
				(width 0)
				(type default)
			)
			(fill no)
			(layer "F.CrtYd")
		)
		(fp_rect
			(start -0.508 0.9398)
			(end 0.508 -0.9398)
			(stroke
				(width 0)
				(type default)
			)
			(fill no)
			(layer "F.Fab")
		)
		(pad "1" smd custom
			(at 0 -0.4445)
			(size 0.1397 0.1397)
			(layers "F.Cu" "F.Mask" "F.Paste")
			(net "P3V3")
			(options
				(clearance outline)
				(anchor circle)
			)
			(primitives
				(gr_poly
					(pts
						(arc
							(start -0.1778 -0.2794)
							(mid -0.249642 -0.249642)
							(end -0.2794 -0.1778)
						)
						(arc
							(start -0.2794 0.1778)
							(mid -0.249642 0.249642)
							(end -0.1778 0.2794)
						)
						(arc
							(start 0.1778 0.2794)
							(mid 0.249642 0.249642)
							(end 0.2794 0.1778)
						)
						(arc
							(start 0.2794 -0.1778)
							(mid 0.249642 -0.249642)
							(end 0.1778 -0.2794)
						)
					)
					(width 0)
					(fill yes)
				)
			)
		)
		(pad "2" smd custom
			(at 0 0.4445)
			(size 0.1397 0.1397)
			(layers "F.Cu" "F.Mask" "F.Paste")
			(net "SELF_TRAY_PRESENT")
			(options
				(clearance outline)
				(anchor circle)
			)
			(primitives
				(gr_poly
					(pts
						(arc
							(start -0.1778 -0.2794)
							(mid -0.249642 -0.249642)
							(end -0.2794 -0.1778)
						)
						(arc
							(start -0.2794 0.1778)
							(mid -0.249642 0.249642)
							(end -0.1778 0.2794)
						)
						(arc
							(start 0.1778 0.2794)
							(mid 0.249642 0.249642)
							(end 0.2794 0.1778)
						)
						(arc
							(start 0.2794 -0.1778)
							(mid 0.249642 -0.249642)
							(end 0.1778 -0.2794)
						)
					)
					(width 0)
					(fill yes)
				)
			)
		)
	)
	(footprint ""
		(layer "F.Cu")
		(at 11.634978 -99.280472 180)
		(property "Reference" "C344"
			(at 0 0 180)
			(layer "F.SilkS")
			(hide yes)
			(effects
				(font
					(size 1.27 1.27)
				)
			)
		)
		(property "Value" "SCD1U50V3KX-GP"
			(at 0 -2.8194 180)
			(unlocked yes)
			(layer "F.Fab")
			(hide yes)
			(effects
				(font
					(size 1.016 1.016)
					(thickness 0.1524)
				)
			)
		)
		(property "Device Type" "C603H36"
			(at 0 -4.3434 180)
			(unlocked yes)
			(layer "F.Fab")
			(hide yes)
			(effects
				(font
					(size 1.016 1.016)
					(thickness 0.1524)
				)
			)
		)
		(duplicate_pad_numbers_are_jumpers no)
		(fp_line
			(start 0.508 0)
			(end -0.508 0)
			(stroke
				(width 0.2032)
				(type default)
			)
			(layer "F.SilkS")
		)
		(fp_rect
			(start -0.5842 1.3335)
			(end 0.5842 -1.3335)
			(stroke
				(width 0)
				(type default)
			)
			(fill no)
			(layer "F.CrtYd")
		)
		(fp_rect
			(start -0.5842 1.3335)
			(end 0.5842 -1.3335)
			(stroke
				(width 0)
				(type default)
			)
			(fill no)
			(layer "F.Fab")
		)
		(pad "1" smd custom
			(at 0 -0.762 180)
			(size 0.2159 0.2159)
			(layers "F.Cu" "F.Mask" "F.Paste")
			(net "P3V3")
			(options
				(clearance outline)
				(anchor circle)
			)
			(primitives
				(gr_poly
					(pts
						(arc
							(start -0.3302 -0.4318)
							(mid -0.402042 -0.402042)
							(end -0.4318 -0.3302)
						)
						(arc
							(start -0.4318 0.3302)
							(mid -0.402042 0.402042)
							(end -0.3302 0.4318)
						)
						(arc
							(start 0.3302 0.4318)
							(mid 0.402042 0.402042)
							(end 0.4318 0.3302)
						)
						(arc
							(start 0.4318 -0.3302)
							(mid 0.402042 -0.402042)
							(end 0.3302 -0.4318)
						)
					)
					(width 0)
					(fill yes)
				)
			)
		)
		(pad "2" smd custom
			(at 0 0.762 180)
			(size 0.2159 0.2159)
			(layers "F.Cu" "F.Mask" "F.Paste")
			(net "GND")
			(options
				(clearance outline)
				(anchor circle)
			)
			(primitives
				(gr_poly
					(pts
						(arc
							(start -0.3302 -0.4318)
							(mid -0.402042 -0.402042)
							(end -0.4318 -0.3302)
						)
						(arc
							(start -0.4318 0.3302)
							(mid -0.402042 0.402042)
							(end -0.3302 0.4318)
						)
						(arc
							(start 0.3302 0.4318)
							(mid 0.402042 0.402042)
							(end 0.4318 0.3302)
						)
						(arc
							(start 0.4318 -0.3302)
							(mid 0.402042 -0.402042)
							(end 0.3302 -0.4318)
						)
					)
					(width 0)
					(fill yes)
				)
			)
		)
	)
	(footprint ""
		(layer "F.Cu")
		(at 156.920692 -103.107744)
		(property "Reference" "PR64"
			(at 0 0 0)
			(layer "F.SilkS")
			(hide yes)
			(effects
				(font
					(size 1.27 1.27)
				)
			)
		)
		(property "Value" "0R3J-0-U-GP"
			(at -0.0254 -2.5146 0)
			(unlocked yes)
			(layer "F.Fab")
			(hide yes)
			(effects
				(font
					(size 1.016 1.016)
					(thickness 0.1524)
				)
			)
		)
		(property "Device Type" "R603H22"
			(at -0.0254 -4.0386 0)
			(unlocked yes)
			(layer "F.Fab")
			(hide yes)
			(effects
				(font
					(size 1.016 1.016)
					(thickness 0.1524)
				)
			)
		)
		(duplicate_pad_numbers_are_jumpers no)
		(fp_line
			(start -0.4826 0)
			(end -0.2032 0)
			(stroke
				(width 0.2032)
				(type default)
			)
			(layer "F.SilkS")
		)
		(fp_line
			(start 0.2032 0)
			(end 0.4826 0)
			(stroke
				(width 0.2032)
				(type default)
			)
			(layer "F.SilkS")
		)
		(fp_rect
			(start -0.5842 1.3335)
			(end 0.5842 -1.3335)
			(stroke
				(width 0)
				(type default)
			)
			(fill no)
			(layer "F.CrtYd")
		)
		(fp_rect
			(start -0.5842 1.3335)
			(end 0.5842 -1.3335)
			(stroke
				(width 0)
				(type default)
			)
			(fill no)
			(layer "F.Fab")
		)
		(pad "1" smd custom
			(at 0 -0.762)
			(size 0.2159 0.2159)
			(layers "F.Cu" "F.Mask" "F.Paste")
			(net "P5VA")
			(options
				(clearance outline)
				(anchor circle)
			)
			(primitives
				(gr_poly
					(pts
						(arc
							(start -0.3302 -0.4318)
							(mid -0.402042 -0.402042)
							(end -0.4318 -0.3302)
						)
						(arc
							(start -0.4318 0.3302)
							(mid -0.402042 0.402042)
							(end -0.3302 0.4318)
						)
						(arc
							(start 0.3302 0.4318)
							(mid 0.402042 0.402042)
							(end 0.4318 0.3302)
						)
						(arc
							(start 0.4318 -0.3302)
							(mid 0.402042 -0.402042)
							(end 0.3302 -0.4318)
						)
					)
					(width 0)
					(fill yes)
				)
			)
		)
		(pad "2" smd custom
			(at 0 0.762)
			(size 0.2159 0.2159)
			(layers "F.Cu" "F.Mask" "F.Paste")
			(net "DETECTOR_C")
			(options
				(clearance outline)
				(anchor circle)
			)
			(primitives
				(gr_poly
					(pts
						(arc
							(start -0.3302 -0.4318)
							(mid -0.402042 -0.402042)
							(end -0.4318 -0.3302)
						)
						(arc
							(start -0.4318 0.3302)
							(mid -0.402042 0.402042)
							(end -0.3302 0.4318)
						)
						(arc
							(start 0.3302 0.4318)
							(mid 0.402042 0.402042)
							(end 0.4318 0.3302)
						)
						(arc
							(start 0.4318 -0.3302)
							(mid 0.402042 -0.402042)
							(end 0.3302 -0.4318)
						)
					)
					(width 0)
					(fill yes)
				)
			)
		)
	)
	(footprint ""
		(layer "F.Cu")
		(at 2.361438 -49.179226 180)
		(property "Reference" "C349"
			(at 0 0 180)
			(layer "F.SilkS")
			(hide yes)
			(effects
				(font
					(size 1.27 1.27)
				)
			)
		)
		(property "Value" "SC10U25V5KX-GP"
			(at -0.0762 -6.1214 180)
			(unlocked yes)
			(layer "F.Fab")
			(hide yes)
			(effects
				(font
					(size 1.016 1.016)
					(thickness 0.1524)
				)
			)
		)
		(property "Device Type" "C805H56"
			(at -0.0762 -8.1534 180)
			(unlocked yes)
			(layer "F.Fab")
			(hide yes)
			(effects
				(font
					(size 1.016 1.016)
					(thickness 0.1524)
				)
			)
		)
		(duplicate_pad_numbers_are_jumpers no)
		(fp_line
			(start 0.635 0)
			(end -0.635 0)
			(stroke
				(width 0.508)
				(type default)
			)
			(layer "F.SilkS")
		)
		(fp_rect
			(start -0.9652 1.778)
			(end 0.9652 -1.778)
			(stroke
				(width 0)
				(type default)
			)
			(fill no)
			(layer "F.CrtYd")
		)
		(fp_poly
			(pts
				(xy -0.9652 -1.778) (xy 0.9652 -1.778) (xy 0.9652 1.778) (xy -0.9652 1.778)
			)
			(stroke
				(width 0)
				(type default)
			)
			(fill no)
			(layer "F.Fab")
		)
		(pad "1" smd rect
			(at 0 -0.9652 180)
			(size 1.397 1.143)
			(layers "F.Cu" "F.Mask" "F.Paste")
			(net "P12V")
		)
		(pad "2" smd rect
			(at 0 0.9652 180)
			(size 1.397 1.143)
			(layers "F.Cu" "F.Mask" "F.Paste")
			(net "GND")
		)
	)
	(footprint ""
		(layer "F.Cu")
		(at 134.375144 -79.273908 180)
		(property "Reference" "Q33"
			(at 0 0 180)
			(layer "F.SilkS")
			(hide yes)
			(effects
				(font
					(size 1.27 1.27)
				)
			)
		)
		(property "Value" "MMBT2222A-3-GP"
			(at 0.10287 -10.29843 180)
			(unlocked yes)
			(layer "F.Fab")
			(hide yes)
			(effects
				(font
					(size 1.016 1.016)
					(thickness 0.1524)
				)
			)
		)
		(property "Device Type" "SOT23CBE2D4H44"
			(at 0.10287 -12.20343 180)
			(unlocked yes)
			(layer "F.Fab")
			(hide yes)
			(effects
				(font
					(size 1.016 1.016)
					(thickness 0.1524)
				)
			)
		)
		(duplicate_pad_numbers_are_jumpers no)
		(fp_line
			(start 1.651 1.778)
			(end 1.651 -1.778)
			(stroke
				(width 0.1524)
				(type default)
			)
			(layer "F.SilkS")
		)
		(fp_line
			(start 1.651 -1.778)
			(end -1.651 -1.778)
			(stroke
				(width 0.1524)
				(type default)
			)
			(layer "F.SilkS")
		)
		(fp_line
			(start -1.651 1.778)
			(end 1.651 1.778)
			(stroke
				(width 0.1524)
				(type default)
			)
			(layer "F.SilkS")
		)
		(fp_line
			(start -1.651 -1.778)
			(end -1.651 1.778)
			(stroke
				(width 0.1524)
				(type default)
			)
			(layer "F.SilkS")
		)
		(fp_poly
			(pts
				(xy -1.778 1.8796) (xy -1.778 -1.8796) (xy 1.778 -1.8796) (xy 1.778 1.8796)
			)
			(stroke
				(width 0)
				(type default)
			)
			(fill no)
			(layer "F.CrtYd")
		)
		(fp_poly
			(pts
				(xy -1.778 1.8796) (xy -1.778 -1.8796) (xy 1.778 -1.8796) (xy 1.778 1.8796)
			)
			(stroke
				(width 0)
				(type default)
			)
			(fill no)
			(layer "F.Fab")
		)
		(pad "B" smd custom
			(at -0.98425 0.9525 180)
			(size 0.1905 0.1905)
			(layers "F.Cu" "F.Mask" "F.Paste")
			(net "TRAY_PRESENT_OUT_NET_B")
			(options
				(clearance outline)
				(anchor circle)
			)
			(primitives
				(gr_poly
					(pts
						(arc
							(start -0.1778 0.5715)
							(mid -0.321484 0.511984)
							(end -0.381 0.3683)
						)
						(arc
							(start -0.381 -0.3683)
							(mid -0.321484 -0.511984)
							(end -0.1778 -0.5715)
						)
						(arc
							(start 0.1778 -0.5715)
							(mid 0.321484 -0.511984)
							(end 0.381 -0.3683)
						)
						(arc
							(start 0.381 0.3683)
							(mid 0.321484 0.511984)
							(end 0.1778 0.5715)
						)
					)
					(width 0)
					(fill yes)
				)
			)
		)
		(pad "C" smd custom
			(at 0 -0.9525 180)
			(size 0.1905 0.1905)
			(layers "F.Cu" "F.Mask" "F.Paste")
			(net "TRAY PRESENT_OUT#_C")
			(options
				(clearance outline)
				(anchor circle)
			)
			(primitives
				(gr_poly
					(pts
						(arc
							(start -0.1778 0.5715)
							(mid -0.321484 0.511984)
							(end -0.381 0.3683)
						)
						(arc
							(start -0.381 -0.3683)
							(mid -0.321484 -0.511984)
							(end -0.1778 -0.5715)
						)
						(arc
							(start 0.1778 -0.5715)
							(mid 0.321484 -0.511984)
							(end 0.381 -0.3683)
						)
						(arc
							(start 0.381 0.3683)
							(mid 0.321484 0.511984)
							(end 0.1778 0.5715)
						)
					)
					(width 0)
					(fill yes)
				)
			)
		)
		(pad "E" smd custom
			(at 0.98425 0.9525 180)
			(size 0.1905 0.1905)
			(layers "F.Cu" "F.Mask" "F.Paste")
			(net "GND")
			(options
				(clearance outline)
				(anchor circle)
			)
			(primitives
				(gr_poly
					(pts
						(arc
							(start -0.1778 0.5715)
							(mid -0.321484 0.511984)
							(end -0.381 0.3683)
						)
						(arc
							(start -0.381 -0.3683)
							(mid -0.321484 -0.511984)
							(end -0.1778 -0.5715)
						)
						(arc
							(start 0.1778 -0.5715)
							(mid 0.321484 -0.511984)
							(end 0.381 -0.3683)
						)
						(arc
							(start 0.381 0.3683)
							(mid 0.321484 0.511984)
							(end 0.1778 0.5715)
						)
					)
					(width 0)
					(fill yes)
				)
			)
		)
	)
	(footprint ""
		(layer "F.Cu")
		(at 12.27455 -89.9541 180)
		(property "Reference" "R343"
			(at 0 0 180)
			(layer "F.SilkS")
			(hide yes)
			(effects
				(font
					(size 1.27 1.27)
				)
			)
		)
		(property "Value" "10KR2F-2-GP"
			(at 0.064008 -3.993896 180)
			(unlocked yes)
			(layer "F.Fab")
			(hide yes)
			(effects
				(font
					(size 1.016 1.016)
					(thickness 0.1524)
				)
			)
		)
		(property "Device Type" "R402H16"
			(at 0.064008 -5.517896 180)
			(unlocked yes)
			(layer "F.Fab")
			(hide yes)
			(effects
				(font
					(size 1.016 1.016)
					(thickness 0.1524)
				)
			)
		)
		(duplicate_pad_numbers_are_jumpers no)
		(fp_line
			(start 0.508 -0.9398)
			(end -0.508 -0.9398)
			(stroke
				(width 0.1524)
				(type default)
			)
			(layer "F.SilkS")
		)
		(fp_line
			(start -0.508 -0.9398)
			(end -0.508 0.9398)
			(stroke
				(width 0.1524)
				(type default)
			)
			(layer "F.SilkS")
		)
		(fp_rect
			(start -0.508 0.9398)
			(end 0.508 -0.9398)
			(stroke
				(width 0)
				(type default)
			)
			(fill no)
			(layer "F.CrtYd")
		)
		(fp_rect
			(start -0.508 0.9398)
			(end 0.508 -0.9398)
			(stroke
				(width 0)
				(type default)
			)
			(fill no)
			(layer "F.Fab")
		)
		(pad "1" smd custom
			(at 0 -0.4445 180)
			(size 0.1397 0.1397)
			(layers "F.Cu" "F.Mask" "F.Paste")
			(net "P3V3")
			(options
				(clearance outline)
				(anchor circle)
			)
			(primitives
				(gr_poly
					(pts
						(arc
							(start -0.1778 -0.2794)
							(mid -0.249642 -0.249642)
							(end -0.2794 -0.1778)
						)
						(arc
							(start -0.2794 0.1778)
							(mid -0.249642 0.249642)
							(end -0.1778 0.2794)
						)
						(arc
							(start 0.1778 0.2794)
							(mid 0.249642 0.249642)
							(end 0.2794 0.1778)
						)
						(arc
							(start 0.2794 -0.1778)
							(mid 0.249642 -0.249642)
							(end 0.1778 -0.2794)
						)
					)
					(width 0)
					(fill yes)
				)
			)
		)
		(pad "2" smd custom
			(at 0 0.4445 180)
			(size 0.1397 0.1397)
			(layers "F.Cu" "F.Mask" "F.Paste")
			(net "I2C_C_BUF_EN")
			(options
				(clearance outline)
				(anchor circle)
			)
			(primitives
				(gr_poly
					(pts
						(arc
							(start -0.1778 -0.2794)
							(mid -0.249642 -0.249642)
							(end -0.2794 -0.1778)
						)
						(arc
							(start -0.2794 0.1778)
							(mid -0.249642 0.249642)
							(end -0.1778 0.2794)
						)
						(arc
							(start 0.1778 0.2794)
							(mid 0.249642 0.249642)
							(end 0.2794 0.1778)
						)
						(arc
							(start 0.2794 -0.1778)
							(mid 0.249642 -0.249642)
							(end 0.1778 -0.2794)
						)
					)
					(width 0)
					(fill yes)
				)
			)
		)
	)
	(footprint ""
		(layer "F.Cu")
		(at 130.299206 -47.183548 180)
		(property "Reference" "TC5"
			(at 0 0 180)
			(layer "F.SilkS")
			(hide yes)
			(effects
				(font
					(size 1.27 1.27)
				)
			)
		)
		(property "Value" "ST68U16VDM-1-GP"
			(at 0 -9.6012 180)
			(unlocked yes)
			(layer "F.Fab")
			(hide yes)
			(effects
				(font
					(size 1.016 1.016)
					(thickness 0.1524)
				)
			)
		)
		(property "Device Type" "CT7343H79"
			(at 0 -11.1252 180)
			(unlocked yes)
			(layer "F.Fab")
			(hide yes)
			(effects
				(font
					(size 1.016 1.016)
					(thickness 0.1524)
				)
			)
		)
		(duplicate_pad_numbers_are_jumpers no)
		(fp_line
			(start 2.286 4.8768)
			(end -2.286 4.8768)
			(stroke
				(width 0.1524)
				(type default)
			)
			(layer "F.SilkS")
		)
		(fp_line
			(start 2.286 2.032)
			(end 2.286 4.8768)
			(stroke
				(width 0.1524)
				(type default)
			)
			(layer "F.SilkS")
		)
		(fp_line
			(start 2.286 -2.032)
			(end 2.286 -4.8768)
			(stroke
				(width 0.1524)
				(type default)
			)
			(layer "F.SilkS")
		)
		(fp_line
			(start 2.286 -4.8768)
			(end -2.286 -4.8768)
			(stroke
				(width 0.1524)
				(type default)
			)
			(layer "F.SilkS")
		)
		(fp_line
			(start 2.1082 -4.699)
			(end -2.1082 -4.699)
			(stroke
				(width 0.508)
				(type default)
			)
			(layer "F.SilkS")
		)
		(fp_line
			(start -2.286 4.8768)
			(end -2.286 2.032)
			(stroke
				(width 0.1524)
				(type default)
			)
			(layer "F.SilkS")
		)
		(fp_line
			(start -2.286 -4.8768)
			(end -2.286 -2.032)
			(stroke
				(width 0.1524)
				(type default)
			)
			(layer "F.SilkS")
		)
		(fp_rect
			(start -2.1463 3.6449)
			(end 2.1463 -3.6449)
			(stroke
				(width 0)
				(type default)
			)
			(fill no)
			(layer "F.CrtYd")
		)
		(fp_poly
			(pts
				(xy -2.54 4.953) (xy -2.54 4.2926) (xy -3.81 4.2926) (xy -3.81 -4.2926) (xy -2.54 -4.2926) (xy -2.54 -4.953)
				(xy 2.54 -4.953) (xy 2.54 -4.2926) (xy 3.81 -4.2926) (xy 3.81 -1.6256) (xy 2.1463 -1.6256) (xy 2.1463 -3.6449)
				(xy -2.1463 -3.6449) (xy -2.1463 3.6449) (xy 2.1463 3.6449) (xy 2.1463 -1.6129) (xy 3.81 -1.6129)
				(xy 3.81 4.2926) (xy 2.54 4.2926) (xy 2.54 4.953)
			)
			(stroke
				(width 0)
				(type default)
			)
			(fill no)
			(layer "F.CrtYd")
		)
		(fp_rect
			(start 2.54 4.2926)
			(end 3.81 -4.2926)
			(stroke
				(width 0)
				(type default)
			)
			(fill no)
			(layer "F.Fab")
		)
		(fp_rect
			(start -2.54 4.953)
			(end 2.54 -4.953)
			(stroke
				(width 0)
				(type default)
			)
			(fill no)
			(layer "F.Fab")
		)
		(fp_rect
			(start -3.81 4.2926)
			(end -2.54 -4.2926)
			(stroke
				(width 0)
				(type default)
			)
			(fill no)
			(layer "F.Fab")
		)
		(pad "1" smd rect
			(at 0 -3.1496 180)
			(size 2.413 2.286)
			(layers "F.Cu" "F.Mask" "F.Paste")
			(net "P12V")
		)
		(pad "2" smd rect
			(at 0 3.1496 180)
			(size 2.413 2.286)
			(layers "F.Cu" "F.Mask" "F.Paste")
			(net "GND")
		)
		(zone
			(layer "F.Cu")
			(hatch none 0.5)
			(connect_pads
				(clearance 0)
			)
			(min_thickness 0.25)
			(keepout
				(tracks allowed)
				(vias not_allowed)
				(pads allowed)
				(copperpour not_allowed)
				(footprints allowed)
			)
			(placement
				(enabled no)
				(sheetname "")
			)
			(fill
				(thermal_gap 0.5)
				(thermal_bridge_width 0.5)
				(island_removal_mode 0)
			)
			(polygon
				(pts
					(xy 128.787906 -45.494448) (xy 128.787906 -42.586148) (xy 131.810506 -42.586148) (xy 131.810506 -45.481748)
					(xy 131.810506 -45.811948) (xy 128.787906 -45.811948)
				)
			)
		)
		(zone
			(layer "F.Cu")
			(hatch none 0.5)
			(connect_pads
				(clearance 0)
			)
			(min_thickness 0.25)
			(keepout
				(tracks allowed)
				(vias not_allowed)
				(pads allowed)
				(copperpour not_allowed)
				(footprints allowed)
			)
			(placement
				(enabled no)
				(sheetname "")
			)
			(fill
				(thermal_gap 0.5)
				(thermal_bridge_width 0.5)
				(island_removal_mode 0)
			)
			(polygon
				(pts
					(xy 131.810506 -51.780948) (xy 128.787906 -51.780948) (xy 128.787906 -48.885348) (xy 128.787906 -48.555148)
					(xy 131.810506 -48.555148) (xy 131.810506 -48.885348)
				)
			)
		)
	)
	(footprint ""
		(layer "F.Cu")
		(at 10.962386 -95.39859)
		(property "Reference" "R486"
			(at 0 0 0)
			(layer "F.SilkS")
			(hide yes)
			(effects
				(font
					(size 1.27 1.27)
				)
			)
		)
		(property "Value" "0R2J-2-GP"
			(at 0.064008 -3.993896 0)
			(unlocked yes)
			(layer "F.Fab")
			(hide yes)
			(effects
				(font
					(size 1.016 1.016)
					(thickness 0.1524)
				)
			)
		)
		(property "Device Type" "R402H16"
			(at 0.064008 -5.517896 0)
			(unlocked yes)
			(layer "F.Fab")
			(hide yes)
			(effects
				(font
					(size 1.016 1.016)
					(thickness 0.1524)
				)
			)
		)
		(duplicate_pad_numbers_are_jumpers no)
		(fp_line
			(start -0.508 -0.9398)
			(end -0.508 0.9398)
			(stroke
				(width 0.1524)
				(type default)
			)
			(layer "F.SilkS")
		)
		(fp_line
			(start 0.508 -0.9398)
			(end -0.508 -0.9398)
			(stroke
				(width 0.1524)
				(type default)
			)
			(layer "F.SilkS")
		)
		(fp_rect
			(start -0.508 0.9398)
			(end 0.508 -0.9398)
			(stroke
				(width 0)
				(type default)
			)
			(fill no)
			(layer "F.CrtYd")
		)
		(fp_rect
			(start -0.508 0.9398)
			(end 0.508 -0.9398)
			(stroke
				(width 0)
				(type default)
			)
			(fill no)
			(layer "F.Fab")
		)
		(pad "1" smd custom
			(at 0 -0.4445)
			(size 0.1397 0.1397)
			(layers "F.Cu" "F.Mask" "F.Paste")
			(net "I2C_C_BUF_SDAOUT")
			(options
				(clearance outline)
				(anchor circle)
			)
			(primitives
				(gr_poly
					(pts
						(arc
							(start -0.1778 -0.2794)
							(mid -0.249642 -0.249642)
							(end -0.2794 -0.1778)
						)
						(arc
							(start -0.2794 0.1778)
							(mid -0.249642 0.249642)
							(end -0.1778 0.2794)
						)
						(arc
							(start 0.1778 0.2794)
							(mid 0.249642 0.249642)
							(end 0.2794 0.1778)
						)
						(arc
							(start 0.2794 -0.1778)
							(mid 0.249642 -0.249642)
							(end 0.1778 -0.2794)
						)
					)
					(width 0)
					(fill yes)
				)
			)
		)
		(pad "2" smd custom
			(at 0 0.4445)
			(size 0.1397 0.1397)
			(layers "F.Cu" "F.Mask" "F.Paste")
			(net "I2C_C_SDA")
			(options
				(clearance outline)
				(anchor circle)
			)
			(primitives
				(gr_poly
					(pts
						(arc
							(start -0.1778 -0.2794)
							(mid -0.249642 -0.249642)
							(end -0.2794 -0.1778)
						)
						(arc
							(start -0.2794 0.1778)
							(mid -0.249642 0.249642)
							(end -0.1778 0.2794)
						)
						(arc
							(start 0.1778 0.2794)
							(mid 0.249642 0.249642)
							(end 0.2794 0.1778)
						)
						(arc
							(start 0.2794 -0.1778)
							(mid 0.249642 -0.249642)
							(end 0.1778 -0.2794)
						)
					)
					(width 0)
					(fill yes)
				)
			)
		)
	)
	(footprint ""
		(layer "F.Cu")
		(at 155.66009 -87.700104 90)
		(property "Reference" "LED16"
			(at 0 0 90)
			(layer "F.SilkS")
			(hide yes)
			(effects
				(font
					(size 1.27 1.27)
				)
			)
		)
		(property "Value" "LED-IR-1-GP"
			(at -3.513074 -0.460502 90)
			(unlocked yes)
			(layer "F.Fab")
			(hide yes)
			(effects
				(font
					(size 1.016 1.016)
					(thickness 0.1524)
				)
			)
		)
		(property "Device Type" "LED3640AKH166"
			(at -3.513074 -1.984502 90)
			(unlocked yes)
			(layer "F.Fab")
			(hide yes)
			(effects
				(font
					(size 1.016 1.016)
					(thickness 0.1524)
				)
			)
		)
		(duplicate_pad_numbers_are_jumpers no)
		(fp_line
			(start 2.0574 -2.6543)
			(end -2.1844 -2.6543)
			(stroke
				(width 0.1524)
				(type default)
			)
			(layer "F.SilkS")
		)
		(fp_line
			(start -2.1844 -2.6543)
			(end -2.1844 2.6543)
			(stroke
				(width 0.1524)
				(type default)
			)
			(layer "F.SilkS")
		)
		(fp_line
			(start 2.0574 2.6543)
			(end 2.0574 -2.6543)
			(stroke
				(width 0.1524)
				(type default)
			)
			(layer "F.SilkS")
		)
		(fp_line
			(start -2.1844 2.6543)
			(end 2.0574 2.6543)
			(stroke
				(width 0.1524)
				(type default)
			)
			(layer "F.SilkS")
		)
		(fp_line
			(start -2.1844 2.8321)
			(end 2.0574 2.8321)
			(stroke
				(width 0.508)
				(type default)
			)
			(layer "F.SilkS")
		)
		(fp_rect
			(start -1.8034 1.9939)
			(end 1.8034 -1.9939)
			(stroke
				(width 0)
				(type default)
			)
			(fill no)
			(layer "F.CrtYd")
		)
		(fp_poly
			(pts
				(xy -2.4384 2.7305) (xy -2.4384 -2.7305) (xy 2.3114 -2.7305) (xy 2.3114 1.98882) (xy 1.8034 1.98882)
				(xy 1.8034 -1.9939) (xy -1.8034 -1.9939) (xy -1.8034 1.9939) (xy 2.3114 1.9939) (xy 2.3114 2.7305)
			)
			(stroke
				(width 0)
				(type default)
			)
			(fill no)
			(layer "F.CrtYd")
		)
		(fp_rect
			(start -2.4384 2.7305)
			(end 2.3114 -2.7305)
			(stroke
				(width 0)
				(type default)
			)
			(fill no)
			(layer "F.Fab")
		)
		(pad "A" smd rect
			(at -0.374904 -1.455674 90)
			(size 3.0988 1.8796)
			(layers "F.Cu" "F.Mask" "F.Paste")
			(net "P3V3")
		)
		(pad "K" smd rect
			(at -0.374904 1.455674 90)
			(size 3.0988 1.8796)
			(layers "F.Cu" "F.Mask" "F.Paste")
			(net "EMITTER_K")
		)
	)
	(footprint ""
		(layer "F.Cu")
		(at 134.368794 -75.439778 180)
		(property "Reference" "Q34"
			(at 0 0 180)
			(layer "F.SilkS")
			(hide yes)
			(effects
				(font
					(size 1.27 1.27)
				)
			)
		)
		(property "Value" "2N7002-11-GP"
			(at 0.127 -8.9662 180)
			(unlocked yes)
			(layer "F.Fab")
			(hide yes)
			(effects
				(font
					(size 1.016 1.016)
					(thickness 0.1524)
				)
			)
		)
		(property "Device Type" "SOT23DGS2D4H44"
			(at 0.127 -10.4902 180)
			(unlocked yes)
			(layer "F.Fab")
			(hide yes)
			(effects
				(font
					(size 1.016 1.016)
					(thickness 0.1524)
				)
			)
		)
		(duplicate_pad_numbers_are_jumpers no)
		(fp_line
			(start 1.651 1.778)
			(end 1.651 -1.778)
			(stroke
				(width 0.1524)
				(type default)
			)
			(layer "F.SilkS")
		)
		(fp_line
			(start 1.651 -1.778)
			(end -1.651 -1.778)
			(stroke
				(width 0.1524)
				(type default)
			)
			(layer "F.SilkS")
		)
		(fp_line
			(start -1.651 1.778)
			(end 1.651 1.778)
			(stroke
				(width 0.1524)
				(type default)
			)
			(layer "F.SilkS")
		)
		(fp_line
			(start -1.651 -1.778)
			(end -1.651 1.778)
			(stroke
				(width 0.1524)
				(type default)
			)
			(layer "F.SilkS")
		)
		(fp_poly
			(pts
				(xy -1.778 1.8796) (xy -1.778 -1.8796) (xy 1.778 -1.8796) (xy 1.778 1.8796)
			)
			(stroke
				(width 0)
				(type default)
			)
			(fill no)
			(layer "F.CrtYd")
		)
		(fp_poly
			(pts
				(xy -1.778 1.8796) (xy -1.778 -1.8796) (xy 1.778 -1.8796) (xy 1.778 1.8796)
			)
			(stroke
				(width 0)
				(type default)
			)
			(fill no)
			(layer "F.Fab")
		)
		(pad "D" smd custom
			(at 0 -0.9525 180)
			(size 0.1905 0.1905)
			(layers "F.Cu" "F.Mask" "F.Paste")
			(net "SELF_TRAY_PRESENT")
			(options
				(clearance outline)
				(anchor circle)
			)
			(primitives
				(gr_poly
					(pts
						(arc
							(start -0.1778 0.5715)
							(mid -0.321484 0.511984)
							(end -0.381 0.3683)
						)
						(arc
							(start -0.381 -0.3683)
							(mid -0.321484 -0.511984)
							(end -0.1778 -0.5715)
						)
						(arc
							(start 0.1778 -0.5715)
							(mid 0.321484 -0.511984)
							(end 0.381 -0.3683)
						)
						(arc
							(start 0.381 0.3683)
							(mid 0.321484 0.511984)
							(end 0.1778 0.5715)
						)
					)
					(width 0)
					(fill yes)
				)
			)
		)
		(pad "G" smd custom
			(at -0.98425 0.9525 180)
			(size 0.1905 0.1905)
			(layers "F.Cu" "F.Mask" "F.Paste")
			(net "TRAY_MOSFET_G")
			(options
				(clearance outline)
				(anchor circle)
			)
			(primitives
				(gr_poly
					(pts
						(arc
							(start -0.1778 0.5715)
							(mid -0.321484 0.511984)
							(end -0.381 0.3683)
						)
						(arc
							(start -0.381 -0.3683)
							(mid -0.321484 -0.511984)
							(end -0.1778 -0.5715)
						)
						(arc
							(start 0.1778 -0.5715)
							(mid 0.321484 -0.511984)
							(end 0.381 -0.3683)
						)
						(arc
							(start 0.381 0.3683)
							(mid 0.321484 0.511984)
							(end 0.1778 0.5715)
						)
					)
					(width 0)
					(fill yes)
				)
			)
		)
		(pad "S" smd custom
			(at 0.98425 0.9525 180)
			(size 0.1905 0.1905)
			(layers "F.Cu" "F.Mask" "F.Paste")
			(net "GND")
			(options
				(clearance outline)
				(anchor circle)
			)
			(primitives
				(gr_poly
					(pts
						(arc
							(start -0.1778 0.5715)
							(mid -0.321484 0.511984)
							(end -0.381 0.3683)
						)
						(arc
							(start -0.381 -0.3683)
							(mid -0.321484 -0.511984)
							(end -0.1778 -0.5715)
						)
						(arc
							(start 0.1778 -0.5715)
							(mid 0.321484 -0.511984)
							(end 0.381 -0.3683)
						)
						(arc
							(start 0.381 0.3683)
							(mid 0.321484 0.511984)
							(end 0.1778 0.5715)
						)
					)
					(width 0)
					(fill yes)
				)
			)
		)
	)
	(footprint ""
		(layer "F.Cu")
		(at 161.159952 -18.999962 180)
		(property "Reference" "LED1"
			(at 0 0 180)
			(layer "F.SilkS")
			(hide yes)
			(effects
				(font
					(size 1.27 1.27)
				)
			)
		)
		(property "Value" "LED-G-203-GP"
			(at -2.6924 -1.4224 180)
			(unlocked yes)
			(layer "F.Fab")
			(hide yes)
			(effects
				(font
					(size 1.016 1.016)
					(thickness 0.1524)
				)
			)
		)
		(property "Device Type" "LED1608AKH26"
			(at -2.6924 -2.9464 180)
			(unlocked yes)
			(layer "F.Fab")
			(hide yes)
			(effects
				(font
					(size 1.016 1.016)
					(thickness 0.1524)
				)
			)
		)
		(duplicate_pad_numbers_are_jumpers no)
		(fp_line
			(start 0.7493 1.651)
			(end 0.7493 1.1811)
			(stroke
				(width 0.3302)
				(type default)
			)
			(layer "F.SilkS")
		)
		(fp_line
			(start 0.6604 1.3716)
			(end -0.6604 1.3716)
			(stroke
				(width 0.1524)
				(type default)
			)
			(layer "F.SilkS")
		)
		(fp_line
			(start 0.6604 -1.3716)
			(end 0.6604 1.3716)
			(stroke
				(width 0.1524)
				(type default)
			)
			(layer "F.SilkS")
		)
		(fp_line
			(start -0.5969 1.5494)
			(end 0.5842 1.5494)
			(stroke
				(width 0.508)
				(type default)
			)
			(layer "F.SilkS")
		)
		(fp_line
			(start -0.6604 1.3716)
			(end -0.6604 -1.3716)
			(stroke
				(width 0.1524)
				(type default)
			)
			(layer "F.SilkS")
		)
		(fp_line
			(start -0.6604 -1.3716)
			(end 0.6604 -1.3716)
			(stroke
				(width 0.1524)
				(type default)
			)
			(layer "F.SilkS")
		)
		(fp_line
			(start -0.7493 1.651)
			(end -0.7493 1.1811)
			(stroke
				(width 0.3302)
				(type default)
			)
			(layer "F.SilkS")
		)
		(fp_rect
			(start -0.6223 1.3335)
			(end 0.6223 -1.3335)
			(stroke
				(width 0)
				(type default)
			)
			(fill no)
			(layer "F.CrtYd")
		)
		(fp_rect
			(start -0.6223 1.3335)
			(end 0.6223 -1.3335)
			(stroke
				(width 0)
				(type default)
			)
			(fill no)
			(layer "F.Fab")
		)
		(pad "A" smd custom
			(at 0 -0.762 180)
			(size 0.2159 0.2159)
			(layers "F.Cu" "F.Mask" "F.Paste")
			(net "TPS2490_LED")
			(options
				(clearance outline)
				(anchor circle)
			)
			(primitives
				(gr_poly
					(pts
						(arc
							(start -0.3302 -0.4318)
							(mid -0.402042 -0.402042)
							(end -0.4318 -0.3302)
						)
						(arc
							(start -0.4318 0.3302)
							(mid -0.402042 0.402042)
							(end -0.3302 0.4318)
						)
						(arc
							(start 0.3302 0.4318)
							(mid 0.402042 0.402042)
							(end 0.4318 0.3302)
						)
						(arc
							(start 0.4318 -0.3302)
							(mid 0.402042 -0.402042)
							(end 0.3302 -0.4318)
						)
					)
					(width 0)
					(fill yes)
				)
			)
		)
		(pad "K" smd custom
			(at 0 0.762 180)
			(size 0.2159 0.2159)
			(layers "F.Cu" "F.Mask" "F.Paste")
			(net "GND")
			(options
				(clearance outline)
				(anchor circle)
			)
			(primitives
				(gr_poly
					(pts
						(arc
							(start -0.3302 -0.4318)
							(mid -0.402042 -0.402042)
							(end -0.4318 -0.3302)
						)
						(arc
							(start -0.4318 0.3302)
							(mid -0.402042 0.402042)
							(end -0.3302 0.4318)
						)
						(arc
							(start 0.3302 0.4318)
							(mid 0.402042 0.402042)
							(end 0.4318 0.3302)
						)
						(arc
							(start 0.4318 -0.3302)
							(mid 0.402042 -0.402042)
							(end 0.3302 -0.4318)
						)
					)
					(width 0)
					(fill yes)
				)
			)
		)
	)
	(footprint ""
		(layer "F.Cu")
		(at 17.2339 -96.071944 90)
		(property "Reference" "R487"
			(at 0 0 90)
			(layer "F.SilkS")
			(hide yes)
			(effects
				(font
					(size 1.27 1.27)
				)
			)
		)
		(property "Value" "0R2J-2-GP"
			(at 0.064008 -3.993896 90)
			(unlocked yes)
			(layer "F.Fab")
			(hide yes)
			(effects
				(font
					(size 1.016 1.016)
					(thickness 0.1524)
				)
			)
		)
		(property "Device Type" "R402H16"
			(at 0.064008 -5.517896 90)
			(unlocked yes)
			(layer "F.Fab")
			(hide yes)
			(effects
				(font
					(size 1.016 1.016)
					(thickness 0.1524)
				)
			)
		)
		(duplicate_pad_numbers_are_jumpers no)
		(fp_line
			(start 0.508 -0.9398)
			(end -0.508 -0.9398)
			(stroke
				(width 0.1524)
				(type default)
			)
			(layer "F.SilkS")
		)
		(fp_line
			(start -0.508 -0.9398)
			(end -0.508 0.9398)
			(stroke
				(width 0.1524)
				(type default)
			)
			(layer "F.SilkS")
		)
		(fp_rect
			(start -0.508 0.9398)
			(end 0.508 -0.9398)
			(stroke
				(width 0)
				(type default)
			)
			(fill no)
			(layer "F.CrtYd")
		)
		(fp_rect
			(start -0.508 0.9398)
			(end 0.508 -0.9398)
			(stroke
				(width 0)
				(type default)
			)
			(fill no)
			(layer "F.Fab")
		)
		(pad "1" smd custom
			(at 0 -0.4445 90)
			(size 0.1397 0.1397)
			(layers "F.Cu" "F.Mask" "F.Paste")
			(net "I2C_C_BUF_SDAIN")
			(options
				(clearance outline)
				(anchor circle)
			)
			(primitives
				(gr_poly
					(pts
						(arc
							(start -0.1778 -0.2794)
							(mid -0.249642 -0.249642)
							(end -0.2794 -0.1778)
						)
						(arc
							(start -0.2794 0.1778)
							(mid -0.249642 0.249642)
							(end -0.1778 0.2794)
						)
						(arc
							(start 0.1778 0.2794)
							(mid 0.249642 0.249642)
							(end 0.2794 0.1778)
						)
						(arc
							(start 0.2794 -0.1778)
							(mid 0.249642 -0.249642)
							(end 0.1778 -0.2794)
						)
					)
					(width 0)
					(fill yes)
				)
			)
		)
		(pad "2" smd custom
			(at 0 0.4445 90)
			(size 0.1397 0.1397)
			(layers "F.Cu" "F.Mask" "F.Paste")
			(net "I2C_C_BUF_SDA")
			(options
				(clearance outline)
				(anchor circle)
			)
			(primitives
				(gr_poly
					(pts
						(arc
							(start -0.1778 -0.2794)
							(mid -0.249642 -0.249642)
							(end -0.2794 -0.1778)
						)
						(arc
							(start -0.2794 0.1778)
							(mid -0.249642 0.249642)
							(end -0.1778 0.2794)
						)
						(arc
							(start 0.1778 0.2794)
							(mid 0.249642 0.249642)
							(end 0.2794 0.1778)
						)
						(arc
							(start 0.2794 -0.1778)
							(mid 0.249642 -0.249642)
							(end 0.1778 -0.2794)
						)
					)
					(width 0)
					(fill yes)
				)
			)
		)
	)
	(footprint ""
		(layer "F.Cu")
		(at 126.659894 -5.999988)
		(property "Reference" "H4"
			(at 0 0 0)
			(layer "F.SilkS")
			(hide yes)
			(effects
				(font
					(size 1.27 1.27)
				)
			)
		)
		(property "Value" "HOLE"
			(at -18.200878 0.089916 0)
			(unlocked yes)
			(layer "F.Fab")
			(hide yes)
			(effects
				(font
					(size 1.016 1.016)
					(thickness 0.1524)
				)
			)
		)
		(property "Device Type" "HOLET827X355B355R158-S"
			(at -18.200878 -1.434084 0)
			(unlocked yes)
			(layer "F.Fab")
			(hide yes)
			(effects
				(font
					(size 1.016 1.016)
					(thickness 0.1524)
				)
			)
		)
		(duplicate_pad_numbers_are_jumpers no)
		(fp_poly
			(pts
				(arc
					(start 4.8133 0)
					(mid -4.8133 0)
					(end 4.8133 0)
				)
			)
			(stroke
				(width 0)
				(type default)
			)
			(fill no)
			(layer "B.CrtYd")
		)
		(fp_poly
			(pts
				(arc
					(start -11.9888 4.8133)
					(mid -16.8021 0)
					(end -11.9888 -4.8133)
				)
				(arc
					(start 0 -4.8133)
					(mid 4.8133 0)
					(end 0 4.8133)
				)
			)
			(stroke
				(width 0)
				(type default)
			)
			(fill no)
			(layer "F.CrtYd")
		)
		(fp_poly
			(pts
				(arc
					(start 4.8133 0)
					(mid -4.8133 0)
					(end 4.8133 0)
				)
			)
			(stroke
				(width 0)
				(type default)
			)
			(fill no)
			(layer "B.Fab")
		)
		(fp_poly
			(pts
				(arc
					(start -11.9888 4.8133)
					(mid -16.8021 0)
					(end -11.9888 -4.8133)
				)
				(arc
					(start 0 -4.8133)
					(mid 4.8133 0)
					(end 0 4.8133)
				)
			)
			(stroke
				(width 0)
				(type default)
			)
			(fill no)
			(layer "F.Fab")
		)
		(pad "1" thru_hole oval
			(at 0 0)
			(size 21.0058 9.017)
			(drill 4.0132
				(offset -5.9944 0)
			)
			(layers "*.Cu" "*.Mask")
			(remove_unused_layers no)
			(net "GND")
			(clearance -7.9883)
			(thermal_gap 0.3048)
			(padstack
				(mode front_inner_back)
				(layer "Inner"
					(shape circle)
					(size 4.4196 4.4196)
					(clearance 0.3048)
				)
				(layer "B.Cu"
					(shape circle)
					(size 9.017 9.017)
					(clearance -1.9939)
				)
			)
		)
	)
	(footprint ""
		(layer "F.Cu")
		(at 135.111744 -82.906108 90)
		(property "Reference" "R374"
			(at 0 0 90)
			(layer "F.SilkS")
			(hide yes)
			(effects
				(font
					(size 1.27 1.27)
				)
			)
		)
		(property "Value" "470KR2F-GP"
			(at 0.064008 -3.993896 90)
			(unlocked yes)
			(layer "F.Fab")
			(hide yes)
			(effects
				(font
					(size 1.016 1.016)
					(thickness 0.1524)
				)
			)
		)
		(property "Device Type" "R402H16"
			(at 0.064008 -5.517896 90)
			(unlocked yes)
			(layer "F.Fab")
			(hide yes)
			(effects
				(font
					(size 1.016 1.016)
					(thickness 0.1524)
				)
			)
		)
		(duplicate_pad_numbers_are_jumpers no)
		(fp_line
			(start 0.508 -0.9398)
			(end -0.508 -0.9398)
			(stroke
				(width 0.1524)
				(type default)
			)
			(layer "F.SilkS")
		)
		(fp_line
			(start -0.508 -0.9398)
			(end -0.508 0.9398)
			(stroke
				(width 0.1524)
				(type default)
			)
			(layer "F.SilkS")
		)
		(fp_rect
			(start -0.508 0.9398)
			(end 0.508 -0.9398)
			(stroke
				(width 0)
				(type default)
			)
			(fill no)
			(layer "F.CrtYd")
		)
		(fp_rect
			(start -0.508 0.9398)
			(end 0.508 -0.9398)
			(stroke
				(width 0)
				(type default)
			)
			(fill no)
			(layer "F.Fab")
		)
		(pad "1" smd custom
			(at 0 -0.4445 90)
			(size 0.1397 0.1397)
			(layers "F.Cu" "F.Mask" "F.Paste")
			(net "TRAY PRESENT_OUT_NET")
			(options
				(clearance outline)
				(anchor circle)
			)
			(primitives
				(gr_poly
					(pts
						(arc
							(start -0.1778 -0.2794)
							(mid -0.249642 -0.249642)
							(end -0.2794 -0.1778)
						)
						(arc
							(start -0.2794 0.1778)
							(mid -0.249642 0.249642)
							(end -0.1778 0.2794)
						)
						(arc
							(start 0.1778 0.2794)
							(mid 0.249642 0.249642)
							(end 0.2794 0.1778)
						)
						(arc
							(start 0.2794 -0.1778)
							(mid 0.249642 -0.249642)
							(end 0.1778 -0.2794)
						)
					)
					(width 0)
					(fill yes)
				)
			)
		)
		(pad "2" smd custom
			(at 0 0.4445 90)
			(size 0.1397 0.1397)
			(layers "F.Cu" "F.Mask" "F.Paste")
			(net "GND")
			(options
				(clearance outline)
				(anchor circle)
			)
			(primitives
				(gr_poly
					(pts
						(arc
							(start -0.1778 -0.2794)
							(mid -0.249642 -0.249642)
							(end -0.2794 -0.1778)
						)
						(arc
							(start -0.2794 0.1778)
							(mid -0.249642 0.249642)
							(end -0.1778 0.2794)
						)
						(arc
							(start 0.1778 0.2794)
							(mid 0.249642 0.249642)
							(end 0.2794 0.1778)
						)
						(arc
							(start 0.2794 -0.1778)
							(mid 0.249642 -0.249642)
							(end 0.1778 -0.2794)
						)
					)
					(width 0)
					(fill yes)
				)
			)
		)
	)
	(footprint ""
		(layer "F.Cu")
		(at 137.795 -69.080634 180)
		(property "Reference" "C360"
			(at 0 0 180)
			(layer "F.SilkS")
			(hide yes)
			(effects
				(font
					(size 1.27 1.27)
				)
			)
		)
		(property "Value" "SC220P50V3JN-GP"
			(at 0 -2.8194 180)
			(unlocked yes)
			(layer "F.Fab")
			(hide yes)
			(effects
				(font
					(size 1.016 1.016)
					(thickness 0.1524)
				)
			)
		)
		(property "Device Type" "C603H36"
			(at 0 -4.3434 180)
			(unlocked yes)
			(layer "F.Fab")
			(hide yes)
			(effects
				(font
					(size 1.016 1.016)
					(thickness 0.1524)
				)
			)
		)
		(duplicate_pad_numbers_are_jumpers no)
		(fp_line
			(start 0.508 0)
			(end -0.508 0)
			(stroke
				(width 0.2032)
				(type default)
			)
			(layer "F.SilkS")
		)
		(fp_rect
			(start -0.5842 1.3335)
			(end 0.5842 -1.3335)
			(stroke
				(width 0)
				(type default)
			)
			(fill no)
			(layer "F.CrtYd")
		)
		(fp_rect
			(start -0.5842 1.3335)
			(end 0.5842 -1.3335)
			(stroke
				(width 0)
				(type default)
			)
			(fill no)
			(layer "F.Fab")
		)
		(pad "1" smd custom
			(at 0 -0.762 180)
			(size 0.2159 0.2159)
			(layers "F.Cu" "F.Mask" "F.Paste")
			(net "I2C_C_BUF_SDA_CONN")
			(options
				(clearance outline)
				(anchor circle)
			)
			(primitives
				(gr_poly
					(pts
						(arc
							(start -0.3302 -0.4318)
							(mid -0.402042 -0.402042)
							(end -0.4318 -0.3302)
						)
						(arc
							(start -0.4318 0.3302)
							(mid -0.402042 0.402042)
							(end -0.3302 0.4318)
						)
						(arc
							(start 0.3302 0.4318)
							(mid 0.402042 0.402042)
							(end 0.4318 0.3302)
						)
						(arc
							(start 0.4318 -0.3302)
							(mid 0.402042 -0.402042)
							(end 0.3302 -0.4318)
						)
					)
					(width 0)
					(fill yes)
				)
			)
		)
		(pad "2" smd custom
			(at 0 0.762 180)
			(size 0.2159 0.2159)
			(layers "F.Cu" "F.Mask" "F.Paste")
			(net "GND")
			(options
				(clearance outline)
				(anchor circle)
			)
			(primitives
				(gr_poly
					(pts
						(arc
							(start -0.3302 -0.4318)
							(mid -0.402042 -0.402042)
							(end -0.4318 -0.3302)
						)
						(arc
							(start -0.4318 0.3302)
							(mid -0.402042 0.402042)
							(end -0.3302 0.4318)
						)
						(arc
							(start 0.3302 0.4318)
							(mid 0.402042 0.402042)
							(end 0.4318 0.3302)
						)
						(arc
							(start 0.4318 -0.3302)
							(mid 0.402042 -0.402042)
							(end 0.3302 -0.4318)
						)
					)
					(width 0)
					(fill yes)
				)
			)
		)
	)
	(gr_line
		(start -10.999978 -76.379832)
		(end -10.999978 -91.45016)
		(stroke
			(width 5.08)
			(type default)
		)
		(layer "In1.Cu")
	)
	(gr_line
		(start -10.999978 -72.680068)
		(end -9.500108 -74.179938)
		(stroke
			(width 1.524)
			(type default)
		)
		(layer "In1.Cu")
	)
	(gr_line
		(start -10.999978 -29.669994)
		(end -10.999978 -72.680068)
		(stroke
			(width 5.08)
			(type default)
		)
		(layer "In1.Cu")
	)
	(gr_line
		(start -9.500108 -92.95003)
		(end -9.500108 -74.879962)
		(stroke
			(width 1.524)
			(type default)
		)
		(layer "In1.Cu")
	)
	(gr_line
		(start -9.500108 -74.879962)
		(end -10.999978 -76.379832)
		(stroke
			(width 1.524)
			(type default)
		)
		(layer "In1.Cu")
	)
	(gr_line
		(start -9.500108 -74.879962)
		(end -0.350012 -74.879962)
		(stroke
			(width 1.524)
			(type default)
		)
		(layer "In1.Cu")
	)
	(gr_line
		(start -9.500108 -74.179938)
		(end -9.500108 -28.170124)
		(stroke
			(width 1.524)
			(type default)
		)
		(layer "In1.Cu")
	)
	(gr_line
		(start -9.500108 -74.179938)
		(end -0.350012 -74.179938)
		(stroke
			(width 1.524)
			(type default)
		)
		(layer "In1.Cu")
	)
	(gr_line
		(start -9.500108 -28.170124)
		(end -0.999998 -28.170124)
		(stroke
			(width 1.524)
			(type default)
		)
		(layer "In1.Cu")
	)
	(gr_line
		(start -8.790178 -49.13376)
		(end 104.267 -49.149)
		(stroke
			(width 0.508)
			(type default)
		)
		(layer "In1.Cu")
	)
	(gr_line
		(start -0.999998 -92.95003)
		(end -9.500108 -92.95003)
		(stroke
			(width 1.524)
			(type default)
		)
		(layer "In1.Cu")
	)
	(gr_arc
		(start -0.999998 -28.170124)
		(mid -0.292893 -27.877231)
		(end 0 -27.170126)
		(stroke
			(width 1.524)
			(type default)
		)
		(layer "In1.Cu")
	)
	(gr_line
		(start -0.350012 -74.879962)
		(end -9.500108 -74.879962)
		(stroke
			(width 1.524)
			(type default)
		)
		(layer "In1.Cu")
	)
	(gr_arc
		(start -0.350012 -74.879962)
		(mid 0 -74.52995)
		(end -0.350012 -74.179938)
		(stroke
			(width 1.524)
			(type default)
		)
		(layer "In1.Cu")
	)
	(gr_line
		(start -0.350012 -74.179938)
		(end -9.500108 -74.179938)
		(stroke
			(width 1.524)
			(type default)
		)
		(layer "In1.Cu")
	)
	(gr_line
		(start 0 -119.000016)
		(end 0 -93.950028)
		(stroke
			(width 1.524)
			(type default)
		)
		(layer "In1.Cu")
	)
	(gr_arc
		(start 0 -119.000016)
		(mid 0.292895 -119.707118)
		(end 0.999998 -120.000014)
		(stroke
			(width 1.524)
			(type default)
		)
		(layer "In1.Cu")
	)
	(gr_arc
		(start 0 -93.950028)
		(mid -0.292893 -93.242923)
		(end -0.999998 -92.95003)
		(stroke
			(width 1.524)
			(type default)
		)
		(layer "In1.Cu")
	)
	(gr_line
		(start 0 -27.170126)
		(end 0 -0.999998)
		(stroke
			(width 1.524)
			(type default)
		)
		(layer "In1.Cu")
	)
	(gr_arc
		(start 0.999998 0)
		(mid 0.292893 -0.292893)
		(end 0 -0.999998)
		(stroke
			(width 1.524)
			(type default)
		)
		(layer "In1.Cu")
	)
	(gr_line
		(start 0.999998 0)
		(end 161.660078 0)
		(stroke
			(width 1.524)
			(type default)
		)
		(layer "In1.Cu")
	)
	(gr_line
		(start 9.779 -20.447)
		(end 0.254 -20.447)
		(stroke
			(width 0.508)
			(type default)
		)
		(layer "In1.Cu")
	)
	(gr_line
		(start 14.097 -16.129)
		(end 9.779 -20.447)
		(stroke
			(width 0.508)
			(type default)
		)
		(layer "In1.Cu")
	)
	(gr_line
		(start 14.224 -16.129)
		(end 14.097 -16.129)
		(stroke
			(width 0.508)
			(type default)
		)
		(layer "In1.Cu")
	)
	(gr_line
		(start 104.267 -49.149)
		(end 106.045 -47.371)
		(stroke
			(width 0.508)
			(type default)
		)
		(layer "In1.Cu")
	)
	(gr_line
		(start 106.045 -47.371)
		(end 140.97 -47.371)
		(stroke
			(width 0.508)
			(type default)
		)
		(layer "In1.Cu")
	)
	(gr_arc
		(start 137.660126 -95.149924)
		(mid 137.953019 -95.857029)
		(end 138.660124 -96.149922)
		(stroke
			(width 1.524)
			(type default)
		)
		(layer "In1.Cu")
	)
	(gr_line
		(start 137.660126 -90.849958)
		(end 137.660126 -95.149924)
		(stroke
			(width 1.524)
			(type default)
		)
		(layer "In1.Cu")
	)
	(gr_line
		(start 138.660124 -96.149922)
		(end 159.357314 -96.149922)
		(stroke
			(width 1.524)
			(type default)
		)
		(layer "In1.Cu")
	)
	(gr_arc
		(start 138.660124 -89.84996)
		(mid 137.953019 -90.142853)
		(end 137.660126 -90.849958)
		(stroke
			(width 1.524)
			(type default)
		)
		(layer "In1.Cu")
	)
	(gr_line
		(start 139.04976 -16.11376)
		(end 14.224 -16.129)
		(stroke
			(width 0.508)
			(type default)
		)
		(layer "In1.Cu")
	)
	(gr_line
		(start 140.97 -47.371)
		(end 143.891 -50.292)
		(stroke
			(width 0.508)
			(type default)
		)
		(layer "In1.Cu")
	)
	(gr_line
		(start 143.891 -50.292)
		(end 153.797 -50.292)
		(stroke
			(width 0.508)
			(type default)
		)
		(layer "In1.Cu")
	)
	(gr_line
		(start 149.86 -36.195)
		(end 149.86 -26.924)
		(stroke
			(width 0.508)
			(type default)
		)
		(layer "In1.Cu")
	)
	(gr_line
		(start 149.86 -26.924)
		(end 139.04976 -16.11376)
		(stroke
			(width 0.508)
			(type default)
		)
		(layer "In1.Cu")
	)
	(gr_line
		(start 153.797 -50.292)
		(end 154.559 -49.53)
		(stroke
			(width 0.508)
			(type default)
		)
		(layer "In1.Cu")
	)
	(gr_line
		(start 154.559 -49.53)
		(end 154.559 -40.894)
		(stroke
			(width 0.508)
			(type default)
		)
		(layer "In1.Cu")
	)
	(gr_line
		(start 154.559 -40.894)
		(end 149.86 -36.195)
		(stroke
			(width 0.508)
			(type default)
		)
		(layer "In1.Cu")
	)
	(gr_arc
		(start 157.660086 -79.462884)
		(mid 157.952979 -80.169989)
		(end 158.660084 -80.462882)
		(stroke
			(width 1.524)
			(type default)
		)
		(layer "In1.Cu")
	)
	(gr_line
		(start 157.660086 -34.536888)
		(end 157.660086 -79.462884)
		(stroke
			(width 1.524)
			(type default)
		)
		(layer "In1.Cu")
	)
	(gr_line
		(start 158.660084 -80.462882)
		(end 161.660078 -80.462882)
		(stroke
			(width 1.524)
			(type default)
		)
		(layer "In1.Cu")
	)
	(gr_arc
		(start 158.660084 -33.53689)
		(mid 157.952979 -33.829783)
		(end 157.660086 -34.536888)
		(stroke
			(width 1.524)
			(type default)
		)
		(layer "In1.Cu")
	)
	(gr_line
		(start 159.357314 -89.84996)
		(end 138.660124 -89.84996)
		(stroke
			(width 1.524)
			(type default)
		)
		(layer "In1.Cu")
	)
	(gr_arc
		(start 159.357314 -89.84996)
		(mid 159.646964 -89.807001)
		(end 159.911796 -89.682066)
		(stroke
			(width 1.524)
			(type default)
		)
		(layer "In1.Cu")
	)
	(gr_arc
		(start 159.911796 -96.31807)
		(mid 159.647001 -96.192954)
		(end 159.357314 -96.149922)
		(stroke
			(width 1.524)
			(type default)
		)
		(layer "In1.Cu")
	)
	(gr_line
		(start 159.911796 -96.31807)
		(end 162.214814 -97.853246)
		(stroke
			(width 1.524)
			(type default)
		)
		(layer "In1.Cu")
	)
	(gr_line
		(start 161.660078 -120.000014)
		(end 0.999998 -120.000014)
		(stroke
			(width 1.524)
			(type default)
		)
		(layer "In1.Cu")
	)
	(gr_arc
		(start 161.660078 -120.000014)
		(mid 162.367203 -119.70713)
		(end 162.660076 -119.000016)
		(stroke
			(width 1.524)
			(type default)
		)
		(layer "In1.Cu")
	)
	(gr_line
		(start 161.660078 -33.53689)
		(end 158.660084 -33.53689)
		(stroke
			(width 1.524)
			(type default)
		)
		(layer "In1.Cu")
	)
	(gr_arc
		(start 161.660078 -33.53689)
		(mid 162.367195 -33.244005)
		(end 162.660076 -32.536892)
		(stroke
			(width 1.524)
			(type default)
		)
		(layer "In1.Cu")
	)
	(gr_line
		(start 162.214814 -88.14689)
		(end 159.911796 -89.682066)
		(stroke
			(width 1.524)
			(type default)
		)
		(layer "In1.Cu")
	)
	(gr_arc
		(start 162.214814 -88.14689)
		(mid 162.541754 -87.786652)
		(end 162.660076 -87.314786)
		(stroke
			(width 1.524)
			(type default)
		)
		(layer "In1.Cu")
	)
	(gr_arc
		(start 162.660076 -98.685096)
		(mid 162.541729 -98.213357)
		(end 162.214814 -97.853246)
		(stroke
			(width 1.524)
			(type default)
		)
		(layer "In1.Cu")
	)
	(gr_line
		(start 162.660076 -98.685096)
		(end 162.660076 -119.000016)
		(stroke
			(width 1.524)
			(type default)
		)
		(layer "In1.Cu")
	)
	(gr_arc
		(start 162.660076 -81.46288)
		(mid 162.367175 -80.755795)
		(end 161.660078 -80.462882)
		(stroke
			(width 1.524)
			(type default)
		)
		(layer "In1.Cu")
	)
	(gr_line
		(start 162.660076 -81.46288)
		(end 162.660076 -87.314786)
		(stroke
			(width 1.524)
			(type default)
		)
		(layer "In1.Cu")
	)
	(gr_arc
		(start 162.660076 -0.999998)
		(mid 162.367181 -0.292902)
		(end 161.660078 0)
		(stroke
			(width 1.524)
			(type default)
		)
		(layer "In1.Cu")
	)
	(gr_line
		(start 162.660076 -0.999998)
		(end 162.660076 -32.536892)
		(stroke
			(width 1.524)
			(type default)
		)
		(layer "In1.Cu")
	)
	(gr_line
		(start -10.999978 -76.379832)
		(end -10.999978 -91.45016)
		(stroke
			(width 5.08)
			(type default)
		)
		(layer "In2.Cu")
	)
	(gr_line
		(start -10.999978 -72.680068)
		(end -9.500108 -74.179938)
		(stroke
			(width 2.54)
			(type default)
		)
		(layer "In2.Cu")
	)
	(gr_line
		(start -10.999978 -29.669994)
		(end -10.999978 -72.680068)
		(stroke
			(width 5.08)
			(type default)
		)
		(layer "In2.Cu")
	)
	(gr_line
		(start -9.500108 -74.879962)
		(end -10.999978 -76.379832)
		(stroke
			(width 2.54)
			(type default)
		)
		(layer "In2.Cu")
	)
	(gr_line
		(start -9.500108 -74.879962)
		(end -0.350012 -74.879962)
		(stroke
			(width 2.54)
			(type default)
		)
		(layer "In2.Cu")
	)
	(gr_line
		(start -9.500108 -74.179938)
		(end -0.350012 -74.179938)
		(stroke
			(width 2.54)
			(type default)
		)
		(layer "In2.Cu")
	)
	(gr_line
		(start -9.500108 -28.170124)
		(end -10.999978 -29.669994)
		(stroke
			(width 2.54)
			(type default)
		)
		(layer "In2.Cu")
	)
	(gr_line
		(start -0.999998 -92.95003)
		(end -9.500108 -92.95003)
		(stroke
			(width 1.524)
			(type default)
		)
		(layer "In2.Cu")
	)
	(gr_line
		(start -0.999998 -28.170124)
		(end -9.500108 -28.170124)
		(stroke
			(width 2.54)
			(type default)
		)
		(layer "In2.Cu")
	)
	(gr_arc
		(start -0.999998 -28.170124)
		(mid -0.292893 -27.877231)
		(end 0 -27.170126)
		(stroke
			(width 2.54)
			(type default)
		)
		(layer "In2.Cu")
	)
	(gr_line
		(start -0.350012 -74.879962)
		(end -9.500108 -74.879962)
		(stroke
			(width 2.54)
			(type default)
		)
		(layer "In2.Cu")
	)
	(gr_arc
		(start -0.350012 -74.879962)
		(mid 0 -74.52995)
		(end -0.350012 -74.179938)
		(stroke
			(width 2.54)
			(type default)
		)
		(layer "In2.Cu")
	)
	(gr_line
		(start -0.350012 -74.179938)
		(end -9.500108 -74.179938)
		(stroke
			(width 2.54)
			(type default)
		)
		(layer "In2.Cu")
	)
	(gr_line
		(start 0 -119.000016)
		(end 0 -93.950028)
		(stroke
			(width 1.524)
			(type default)
		)
		(layer "In2.Cu")
	)
	(gr_arc
		(start 0 -119.000016)
		(mid 0.292895 -119.707118)
		(end 0.999998 -120.000014)
		(stroke
			(width 1.524)
			(type default)
		)
		(layer "In2.Cu")
	)
	(gr_arc
		(start 0 -93.950028)
		(mid -0.292893 -93.242923)
		(end -0.999998 -92.95003)
		(stroke
			(width 1.524)
			(type default)
		)
		(layer "In2.Cu")
	)
	(gr_line
		(start 0 -27.170126)
		(end 0 -0.999998)
		(stroke
			(width 2.54)
			(type default)
		)
		(layer "In2.Cu")
	)
	(gr_line
		(start 0.254 -20.447)
		(end 9.779 -20.447)
		(stroke
			(width 0.508)
			(type default)
		)
		(layer "In2.Cu")
	)
	(gr_arc
		(start 0.999998 0)
		(mid 0.292893 -0.292893)
		(end 0 -0.999998)
		(stroke
			(width 1.524)
			(type default)
		)
		(layer "In2.Cu")
	)
	(gr_line
		(start 0.999998 0)
		(end 161.660078 0)
		(stroke
			(width 1.524)
			(type default)
		)
		(layer "In2.Cu")
	)
	(gr_line
		(start 9.779 -20.447)
		(end 14.097 -16.129)
		(stroke
			(width 0.508)
			(type default)
		)
		(layer "In2.Cu")
	)
	(gr_line
		(start 14.097 -16.129)
		(end 14.224 -16.129)
		(stroke
			(width 0.508)
			(type default)
		)
		(layer "In2.Cu")
	)
	(gr_line
		(start 14.224 -16.129)
		(end 139.04976 -16.11376)
		(stroke
			(width 0.508)
			(type default)
		)
		(layer "In2.Cu")
	)
	(gr_line
		(start 104.267 -49.149)
		(end -8.790178 -49.13376)
		(stroke
			(width 0.508)
			(type default)
		)
		(layer "In2.Cu")
	)
	(gr_line
		(start 106.045 -47.371)
		(end 104.267 -49.149)
		(stroke
			(width 0.508)
			(type default)
		)
		(layer "In2.Cu")
	)
	(gr_line
		(start 123.670822 -47.35576)
		(end 106.045 -47.371)
		(stroke
			(width 0.508)
			(type default)
		)
		(layer "In2.Cu")
	)
	(gr_arc
		(start 137.660126 -95.149924)
		(mid 137.953019 -95.857029)
		(end 138.660124 -96.149922)
		(stroke
			(width 1.524)
			(type default)
		)
		(layer "In2.Cu")
	)
	(gr_line
		(start 137.660126 -90.849958)
		(end 137.660126 -95.149924)
		(stroke
			(width 1.524)
			(type default)
		)
		(layer "In2.Cu")
	)
	(gr_line
		(start 138.660124 -96.149922)
		(end 159.357314 -96.149922)
		(stroke
			(width 1.524)
			(type default)
		)
		(layer "In2.Cu")
	)
	(gr_arc
		(start 138.660124 -89.84996)
		(mid 137.953019 -90.142853)
		(end 137.660126 -90.849958)
		(stroke
			(width 1.524)
			(type default)
		)
		(layer "In2.Cu")
	)
	(gr_line
		(start 139.04976 -16.11376)
		(end 149.86 -26.924)
		(stroke
			(width 0.508)
			(type default)
		)
		(layer "In2.Cu")
	)
	(gr_line
		(start 140.97 -47.371)
		(end 123.670822 -47.35576)
		(stroke
			(width 0.508)
			(type default)
		)
		(layer "In2.Cu")
	)
	(gr_line
		(start 143.891 -50.292)
		(end 140.97 -47.371)
		(stroke
			(width 0.508)
			(type default)
		)
		(layer "In2.Cu")
	)
	(gr_line
		(start 149.86 -36.195)
		(end 154.559 -40.894)
		(stroke
			(width 0.508)
			(type default)
		)
		(layer "In2.Cu")
	)
	(gr_line
		(start 149.86 -26.924)
		(end 149.86 -36.195)
		(stroke
			(width 0.508)
			(type default)
		)
		(layer "In2.Cu")
	)
	(gr_line
		(start 153.797 -50.292)
		(end 143.891 -50.292)
		(stroke
			(width 0.508)
			(type default)
		)
		(layer "In2.Cu")
	)
	(gr_line
		(start 154.559 -49.53)
		(end 153.797 -50.292)
		(stroke
			(width 0.508)
			(type default)
		)
		(layer "In2.Cu")
	)
	(gr_line
		(start 154.559 -40.894)
		(end 154.559 -49.53)
		(stroke
			(width 0.508)
			(type default)
		)
		(layer "In2.Cu")
	)
	(gr_arc
		(start 157.660086 -79.462884)
		(mid 157.952979 -80.169989)
		(end 158.660084 -80.462882)
		(stroke
			(width 1.524)
			(type default)
		)
		(layer "In2.Cu")
	)
	(gr_line
		(start 157.660086 -34.536888)
		(end 157.660086 -79.462884)
		(stroke
			(width 1.524)
			(type default)
		)
		(layer "In2.Cu")
	)
	(gr_line
		(start 158.660084 -80.462882)
		(end 161.660078 -80.462882)
		(stroke
			(width 1.524)
			(type default)
		)
		(layer "In2.Cu")
	)
	(gr_arc
		(start 158.660084 -33.53689)
		(mid 157.952979 -33.829783)
		(end 157.660086 -34.536888)
		(stroke
			(width 1.524)
			(type default)
		)
		(layer "In2.Cu")
	)
	(gr_line
		(start 159.357314 -89.84996)
		(end 138.660124 -89.84996)
		(stroke
			(width 1.524)
			(type default)
		)
		(layer "In2.Cu")
	)
	(gr_arc
		(start 159.357314 -89.84996)
		(mid 159.646964 -89.807001)
		(end 159.911796 -89.682066)
		(stroke
			(width 1.524)
			(type default)
		)
		(layer "In2.Cu")
	)
	(gr_arc
		(start 159.911796 -96.31807)
		(mid 159.647001 -96.192954)
		(end 159.357314 -96.149922)
		(stroke
			(width 1.524)
			(type default)
		)
		(layer "In2.Cu")
	)
	(gr_line
		(start 159.911796 -96.31807)
		(end 162.214814 -97.853246)
		(stroke
			(width 1.524)
			(type default)
		)
		(layer "In2.Cu")
	)
	(gr_line
		(start 161.660078 -120.000014)
		(end 0.999998 -120.000014)
		(stroke
			(width 1.524)
			(type default)
		)
		(layer "In2.Cu")
	)
	(gr_arc
		(start 161.660078 -120.000014)
		(mid 162.367203 -119.70713)
		(end 162.660076 -119.000016)
		(stroke
			(width 1.524)
			(type default)
		)
		(layer "In2.Cu")
	)
	(gr_line
		(start 161.660078 -33.53689)
		(end 158.660084 -33.53689)
		(stroke
			(width 1.524)
			(type default)
		)
		(layer "In2.Cu")
	)
	(gr_arc
		(start 161.660078 -33.53689)
		(mid 162.367195 -33.244005)
		(end 162.660076 -32.536892)
		(stroke
			(width 1.524)
			(type default)
		)
		(layer "In2.Cu")
	)
	(gr_line
		(start 162.214814 -88.14689)
		(end 159.911796 -89.682066)
		(stroke
			(width 1.524)
			(type default)
		)
		(layer "In2.Cu")
	)
	(gr_arc
		(start 162.214814 -88.14689)
		(mid 162.541754 -87.786652)
		(end 162.660076 -87.314786)
		(stroke
			(width 1.524)
			(type default)
		)
		(layer "In2.Cu")
	)
	(gr_arc
		(start 162.660076 -98.685096)
		(mid 162.541729 -98.213357)
		(end 162.214814 -97.853246)
		(stroke
			(width 1.524)
			(type default)
		)
		(layer "In2.Cu")
	)
	(gr_line
		(start 162.660076 -98.685096)
		(end 162.660076 -119.000016)
		(stroke
			(width 1.524)
			(type default)
		)
		(layer "In2.Cu")
	)
	(gr_arc
		(start 162.660076 -81.46288)
		(mid 162.367175 -80.755795)
		(end 161.660078 -80.462882)
		(stroke
			(width 1.524)
			(type default)
		)
		(layer "In2.Cu")
	)
	(gr_line
		(start 162.660076 -81.46288)
		(end 162.660076 -87.314786)
		(stroke
			(width 1.524)
			(type default)
		)
		(layer "In2.Cu")
	)
	(gr_arc
		(start 162.660076 -0.999998)
		(mid 162.367181 -0.292902)
		(end 161.660078 0)
		(stroke
			(width 1.524)
			(type default)
		)
		(layer "In2.Cu")
	)
	(gr_line
		(start 162.660076 -0.999998)
		(end 162.660076 -32.536892)
		(stroke
			(width 1.524)
			(type default)
		)
		(layer "In2.Cu")
	)
	(gr_line
		(start -9.500108 -92.95003)
		(end -9.500108 -74.879962)
		(stroke
			(width 0.05)
			(type default)
		)
		(layer "Edge.Cuts")
	)
	(gr_line
		(start -9.500108 -74.879962)
		(end -0.350012 -74.879962)
		(stroke
			(width 0.05)
			(type default)
		)
		(layer "Edge.Cuts")
	)
	(gr_line
		(start -9.500108 -74.179938)
		(end -9.500108 -28.170124)
		(stroke
			(width 0.05)
			(type default)
		)
		(layer "Edge.Cuts")
	)
	(gr_line
		(start -9.500108 -28.170124)
		(end -0.999998 -28.170124)
		(stroke
			(width 0.05)
			(type default)
		)
		(layer "Edge.Cuts")
	)
	(gr_line
		(start -0.999998 -92.95003)
		(end -9.500108 -92.95003)
		(stroke
			(width 0.05)
			(type default)
		)
		(layer "Edge.Cuts")
	)
	(gr_arc
		(start -0.999998 -28.170124)
		(mid -0.292893 -27.877231)
		(end 0 -27.170126)
		(stroke
			(width 0.05)
			(type default)
		)
		(layer "Edge.Cuts")
	)
	(gr_arc
		(start -0.350012 -74.879962)
		(mid 0 -74.52995)
		(end -0.350012 -74.179938)
		(stroke
			(width 0.05)
			(type default)
		)
		(layer "Edge.Cuts")
	)
	(gr_line
		(start -0.350012 -74.179938)
		(end -9.500108 -74.179938)
		(stroke
			(width 0.05)
			(type default)
		)
		(layer "Edge.Cuts")
	)
	(gr_line
		(start 0 -119.000016)
		(end 0 -93.950028)
		(stroke
			(width 0.05)
			(type default)
		)
		(layer "Edge.Cuts")
	)
	(gr_arc
		(start 0 -119.000016)
		(mid 0.292895 -119.707118)
		(end 0.999998 -120.000014)
		(stroke
			(width 0.05)
			(type default)
		)
		(layer "Edge.Cuts")
	)
	(gr_arc
		(start 0 -93.950028)
		(mid -0.292893 -93.242923)
		(end -0.999998 -92.95003)
		(stroke
			(width 0.05)
			(type default)
		)
		(layer "Edge.Cuts")
	)
	(gr_line
		(start 0 -27.170126)
		(end 0 -0.999998)
		(stroke
			(width 0.05)
			(type default)
		)
		(layer "Edge.Cuts")
	)
	(gr_arc
		(start 0.999998 0)
		(mid 0.292893 -0.292893)
		(end 0 -0.999998)
		(stroke
			(width 0.05)
			(type default)
		)
		(layer "Edge.Cuts")
	)
	(gr_line
		(start 0.999998 0)
		(end 161.660078 0)
		(stroke
			(width 0.05)
			(type default)
		)
		(layer "Edge.Cuts")
	)
	(gr_arc
		(start 4.379976 -62.500002)
		(mid 4.672869 -63.207107)
		(end 5.379974 -63.5)
		(stroke
			(width 0.05)
			(type default)
		)
		(layer "Edge.Cuts")
	)
	(gr_line
		(start 4.379976 -57.500012)
		(end 4.379976 -62.500002)
		(stroke
			(width 0.05)
			(type default)
		)
		(layer "Edge.Cuts")
	)
	(gr_line
		(start 5.379974 -63.5)
		(end 6.379972 -63.5)
		(stroke
			(width 0.05)
			(type default)
		)
		(layer "Edge.Cuts")
	)
	(gr_arc
		(start 5.379974 -56.500014)
		(mid 4.672869 -56.792907)
		(end 4.379976 -57.500012)
		(stroke
			(width 0.05)
			(type default)
		)
		(layer "Edge.Cuts")
	)
	(gr_arc
		(start 6.379972 -63.5)
		(mid 7.087077 -63.207107)
		(end 7.37997 -62.500002)
		(stroke
			(width 0.05)
			(type default)
		)
		(layer "Edge.Cuts")
	)
	(gr_line
		(start 6.379972 -56.500014)
		(end 5.379974 -56.500014)
		(stroke
			(width 0.05)
			(type default)
		)
		(layer "Edge.Cuts")
	)
	(gr_line
		(start 7.37997 -62.500002)
		(end 7.37997 -57.500012)
		(stroke
			(width 0.05)
			(type default)
		)
		(layer "Edge.Cuts")
	)
	(gr_arc
		(start 7.37997 -57.500012)
		(mid 7.087077 -56.792907)
		(end 6.379972 -56.500014)
		(stroke
			(width 0.05)
			(type default)
		)
		(layer "Edge.Cuts")
	)
	(gr_arc
		(start 137.660126 -95.149924)
		(mid 137.953019 -95.857029)
		(end 138.660124 -96.149922)
		(stroke
			(width 0.05)
			(type default)
		)
		(layer "Edge.Cuts")
	)
	(gr_line
		(start 137.660126 -90.849958)
		(end 137.660126 -95.149924)
		(stroke
			(width 0.05)
			(type default)
		)
		(layer "Edge.Cuts")
	)
	(gr_line
		(start 138.660124 -96.149922)
		(end 159.357314 -96.149922)
		(stroke
			(width 0.05)
			(type default)
		)
		(layer "Edge.Cuts")
	)
	(gr_arc
		(start 138.660124 -89.84996)
		(mid 137.953019 -90.142853)
		(end 137.660126 -90.849958)
		(stroke
			(width 0.05)
			(type default)
		)
		(layer "Edge.Cuts")
	)
	(gr_arc
		(start 157.660086 -79.462884)
		(mid 157.952979 -80.169989)
		(end 158.660084 -80.462882)
		(stroke
			(width 0.05)
			(type default)
		)
		(layer "Edge.Cuts")
	)
	(gr_line
		(start 157.660086 -34.536888)
		(end 157.660086 -79.462884)
		(stroke
			(width 0.05)
			(type default)
		)
		(layer "Edge.Cuts")
	)
	(gr_line
		(start 158.660084 -80.462882)
		(end 161.660078 -80.462882)
		(stroke
			(width 0.05)
			(type default)
		)
		(layer "Edge.Cuts")
	)
	(gr_arc
		(start 158.660084 -33.53689)
		(mid 157.952979 -33.829783)
		(end 157.660086 -34.536888)
		(stroke
			(width 0.05)
			(type default)
		)
		(layer "Edge.Cuts")
	)
	(gr_line
		(start 159.357314 -89.84996)
		(end 138.660124 -89.84996)
		(stroke
			(width 0.05)
			(type default)
		)
		(layer "Edge.Cuts")
	)
	(gr_arc
		(start 159.357314 -89.84996)
		(mid 159.646964 -89.807001)
		(end 159.911796 -89.682066)
		(stroke
			(width 0.05)
			(type default)
		)
		(layer "Edge.Cuts")
	)
	(gr_arc
		(start 159.911796 -96.31807)
		(mid 159.647001 -96.192954)
		(end 159.357314 -96.149922)
		(stroke
			(width 0.05)
			(type default)
		)
		(layer "Edge.Cuts")
	)
	(gr_line
		(start 159.911796 -96.31807)
		(end 162.214814 -97.853246)
		(stroke
			(width 0.05)
			(type default)
		)
		(layer "Edge.Cuts")
	)
	(gr_line
		(start 161.660078 -120.000014)
		(end 0.999998 -120.000014)
		(stroke
			(width 0.05)
			(type default)
		)
		(layer "Edge.Cuts")
	)
	(gr_arc
		(start 161.660078 -120.000014)
		(mid 162.367203 -119.70713)
		(end 162.660076 -119.000016)
		(stroke
			(width 0.05)
			(type default)
		)
		(layer "Edge.Cuts")
	)
	(gr_line
		(start 161.660078 -33.53689)
		(end 158.660084 -33.53689)
		(stroke
			(width 0.05)
			(type default)
		)
		(layer "Edge.Cuts")
	)
	(gr_arc
		(start 161.660078 -33.53689)
		(mid 162.367195 -33.244005)
		(end 162.660076 -32.536892)
		(stroke
			(width 0.05)
			(type default)
		)
		(layer "Edge.Cuts")
	)
	(gr_line
		(start 162.214814 -88.14689)
		(end 159.911796 -89.682066)
		(stroke
			(width 0.05)
			(type default)
		)
		(layer "Edge.Cuts")
	)
	(gr_arc
		(start 162.214814 -88.14689)
		(mid 162.541754 -87.786652)
		(end 162.660076 -87.314786)
		(stroke
			(width 0.05)
			(type default)
		)
		(layer "Edge.Cuts")
	)
	(gr_arc
		(start 162.660076 -98.685096)
		(mid 162.541729 -98.213357)
		(end 162.214814 -97.853246)
		(stroke
			(width 0.05)
			(type default)
		)
		(layer "Edge.Cuts")
	)
	(gr_line
		(start 162.660076 -98.685096)
		(end 162.660076 -119.000016)
		(stroke
			(width 0.05)
			(type default)
		)
		(layer "Edge.Cuts")
	)
	(gr_arc
		(start 162.660076 -81.46288)
		(mid 162.367175 -80.755795)
		(end 161.660078 -80.462882)
		(stroke
			(width 0.05)
			(type default)
		)
		(layer "Edge.Cuts")
	)
	(gr_line
		(start 162.660076 -81.46288)
		(end 162.660076 -87.314786)
		(stroke
			(width 0.05)
			(type default)
		)
		(layer "Edge.Cuts")
	)
	(gr_arc
		(start 162.660076 -0.999998)
		(mid 162.367181 -0.292902)
		(end 161.660078 0)
		(stroke
			(width 0.05)
			(type default)
		)
		(layer "Edge.Cuts")
	)
	(gr_line
		(start 162.660076 -0.999998)
		(end 162.660076 -32.536892)
		(stroke
			(width 0.05)
			(type default)
		)
		(layer "Edge.Cuts")
	)
	(segment
		(start 143.764 -106.426)
		(end 139.1285 -106.426)
		(width 0.1397)
		(layer "F.Cu")
		(net "TPS2490_DISABLE")
	)
	(segment
		(start 145.159984 -107.821984)
		(end 143.764 -106.426)
		(width 0.1397)
		(layer "F.Cu")
		(net "TPS2490_DISABLE")
	)
	(segment
		(start 145.159984 -110.000034)
		(end 145.159984 -107.821984)
		(width 0.1397)
		(layer "F.Cu")
		(net "TPS2490_DISABLE")
	)
	(segment
		(start 7.634732 -93.708728)
		(end 6.617208 -93.708728)
		(width 0.1397)
		(layer "F.Cu")
		(net "STRADDLE_I2C_C_SCL")
	)
	(segment
		(start 6.617208 -93.708728)
		(end 5.940044 -93.031564)
		(width 0.1397)
		(layer "F.Cu")
		(net "STRADDLE_I2C_C_SCL")
	)
	(segment
		(start 5.940044 -91.794838)
		(end 1.446276 -87.30107)
		(width 0.1397)
		(layer "F.Cu")
		(net "STRADDLE_I2C_C_SCL")
	)
	(segment
		(start 5.940044 -93.031564)
		(end 5.940044 -91.794838)
		(width 0.1397)
		(layer "F.Cu")
		(net "STRADDLE_I2C_C_SCL")
	)
	(via
		(at 1.446276 -87.30107)
		(size 0.7112)
		(drill 0.4064)
		(layers "F.Cu" "B.Cu")
		(net "STRADDLE_I2C_C_SCL")
	)
	(via
		(at 0.41529 -88.332056)
		(size 0.7112)
		(drill 0.3556)
		(layers "F.Cu" "B.Cu")
		(net "STRADDLE_I2C_C_SCL")
	)
	(segment
		(start -0.711962 -89.459308)
		(end 0.41529 -88.332056)
		(width 0.1397)
		(layer "B.Cu")
		(net "STRADDLE_I2C_C_SCL")
	)
	(segment
		(start 1.446276 -87.30107)
		(end 0.41529 -88.332056)
		(width 0.1397)
		(layer "B.Cu")
		(net "STRADDLE_I2C_C_SCL")
	)
	(segment
		(start -6.61797 -89.459308)
		(end -0.711962 -89.459308)
		(width 0.1397)
		(layer "B.Cu")
		(net "STRADDLE_I2C_C_SCL")
	)
	(segment
		(start 5.094478 -93.157802)
		(end 5.094478 -92.016072)
		(width 0.1397)
		(layer "F.Cu")
		(net "STRADDLE_I2C_C_SDA")
	)
	(segment
		(start 5.094478 -92.016072)
		(end 0.379476 -87.30107)
		(width 0.1397)
		(layer "F.Cu")
		(net "STRADDLE_I2C_C_SDA")
	)
	(segment
		(start 7.634732 -95.029528)
		(end 6.966204 -95.029528)
		(width 0.1397)
		(layer "F.Cu")
		(net "STRADDLE_I2C_C_SDA")
	)
	(segment
		(start 6.966204 -95.029528)
		(end 5.094478 -93.157802)
		(width 0.1397)
		(layer "F.Cu")
		(net "STRADDLE_I2C_C_SDA")
	)
	(via
		(at -0.691388 -86.614)
		(size 0.7112)
		(drill 0.3556)
		(layers "F.Cu" "B.Cu")
		(net "STRADDLE_I2C_C_SDA")
	)
	(via
		(at 0.379476 -87.30107)
		(size 0.7112)
		(drill 0.4064)
		(layers "F.Cu" "B.Cu")
		(net "STRADDLE_I2C_C_SDA")
	)
	(segment
		(start -2.869692 -86.614)
		(end -0.691388 -86.614)
		(width 0.1397)
		(layer "B.Cu")
		(net "STRADDLE_I2C_C_SDA")
	)
	(segment
		(start -6.61797 -86.919308)
		(end -3.175 -86.919308)
		(width 0.1397)
		(layer "B.Cu")
		(net "STRADDLE_I2C_C_SDA")
	)
	(segment
		(start -3.175 -86.919308)
		(end -2.869692 -86.614)
		(width 0.1397)
		(layer "B.Cu")
		(net "STRADDLE_I2C_C_SDA")
	)
	(segment
		(start 0.379476 -87.30107)
		(end -0.307594 -86.614)
		(width 0.1397)
		(layer "B.Cu")
		(net "STRADDLE_I2C_C_SDA")
	)
	(segment
		(start -0.307594 -86.614)
		(end -0.691388 -86.614)
		(width 0.1397)
		(layer "B.Cu")
		(net "STRADDLE_I2C_C_SDA")
	)
	(segment
		(start 14.059408 -98.380296)
		(end 14.059408 -97.978214)
		(width 0.1397)
		(layer "F.Cu")
		(net "I2C_C_BUF_SDAIN")
	)
	(segment
		(start 13.975588 -97.894394)
		(end 13.975588 -96.431608)
		(width 0.1397)
		(layer "F.Cu")
		(net "I2C_C_BUF_SDAIN")
	)
	(segment
		(start 15.952216 -95.23476)
		(end 16.7894 -96.071944)
		(width 0.1397)
		(layer "F.Cu")
		(net "I2C_C_BUF_SDAIN")
	)
	(segment
		(start 14.148054 -95.23476)
		(end 15.952216 -95.23476)
		(width 0.1397)
		(layer "F.Cu")
		(net "I2C_C_BUF_SDAIN")
	)
	(segment
		(start 14.059408 -97.978214)
		(end 13.975588 -97.894394)
		(width 0.1397)
		(layer "F.Cu")
		(net "I2C_C_BUF_SDAIN")
	)
	(segment
		(start 16.7894 -96.071944)
		(end 16.7894 -97.411032)
		(width 0.1397)
		(layer "F.Cu")
		(net "I2C_C_BUF_SDAIN")
	)
	(segment
		(start 13.975588 -96.431608)
		(end 13.975588 -95.407226)
		(width 0.1397)
		(layer "F.Cu")
		(net "I2C_C_BUF_SDAIN")
	)
	(segment
		(start 13.975588 -95.407226)
		(end 14.148054 -95.23476)
		(width 0.1397)
		(layer "F.Cu")
		(net "I2C_C_BUF_SDAIN")
	)
	(via
		(at 16.7894 -97.411032)
		(size 0.7112)
		(drill 0.3556)
		(layers "F.Cu" "B.Cu")
		(net "I2C_C_BUF_SDAIN")
	)
	(segment
		(start 10.962386 -95.84309)
		(end 10.962386 -97.182178)
		(width 0.1397)
		(layer "F.Cu")
		(net "I2C_C_BUF_SDAOUT")
	)
	(segment
		(start 13.163804 -95.30461)
		(end 11.500866 -95.30461)
		(width 0.1397)
		(layer "F.Cu")
		(net "I2C_C_BUF_SDAOUT")
	)
	(segment
		(start 13.325348 -98.020378)
		(end 13.325348 -96.431608)
		(width 0.1397)
		(layer "F.Cu")
		(net "I2C_C_BUF_SDAOUT")
	)
	(segment
		(start 12.977876 -98.36785)
		(end 13.325348 -98.020378)
		(width 0.1397)
		(layer "F.Cu")
		(net "I2C_C_BUF_SDAOUT")
	)
	(segment
		(start 11.500866 -95.30461)
		(end 10.962386 -95.84309)
		(width 0.1397)
		(layer "F.Cu")
		(net "I2C_C_BUF_SDAOUT")
	)
	(segment
		(start 13.325348 -96.431608)
		(end 13.325348 -95.466154)
		(width 0.1397)
		(layer "F.Cu")
		(net "I2C_C_BUF_SDAOUT")
	)
	(segment
		(start 13.325348 -95.466154)
		(end 13.163804 -95.30461)
		(width 0.1397)
		(layer "F.Cu")
		(net "I2C_C_BUF_SDAOUT")
	)
	(via
		(at 10.962386 -97.182178)
		(size 0.7112)
		(drill 0.3556)
		(layers "F.Cu" "B.Cu")
		(net "I2C_C_BUF_SDAOUT")
	)
	(segment
		(start 14.177264 -93.420946)
		(end 16.10487 -93.420946)
		(width 0.1397)
		(layer "F.Cu")
		(net "I2C_C_BUF_SCLIN")
	)
	(segment
		(start 16.774414 -92.751402)
		(end 16.774414 -91.412314)
		(width 0.1397)
		(layer "F.Cu")
		(net "I2C_C_BUF_SCLIN")
	)
	(segment
		(start 13.975588 -91.004644)
		(end 13.975588 -92.291408)
		(width 0.1397)
		(layer "F.Cu")
		(net "I2C_C_BUF_SCLIN")
	)
	(segment
		(start 14.579092 -90.40114)
		(end 13.975588 -91.004644)
		(width 0.1397)
		(layer "F.Cu")
		(net "I2C_C_BUF_SCLIN")
	)
	(segment
		(start 16.10487 -93.420946)
		(end 16.774414 -92.751402)
		(width 0.1397)
		(layer "F.Cu")
		(net "I2C_C_BUF_SCLIN")
	)
	(segment
		(start 13.975588 -92.291408)
		(end 13.975588 -93.21927)
		(width 0.1397)
		(layer "F.Cu")
		(net "I2C_C_BUF_SCLIN")
	)
	(segment
		(start 13.975588 -93.21927)
		(end 14.177264 -93.420946)
		(width 0.1397)
		(layer "F.Cu")
		(net "I2C_C_BUF_SCLIN")
	)
	(via
		(at 16.774414 -91.412314)
		(size 0.7112)
		(drill 0.3556)
		(layers "F.Cu" "B.Cu")
		(net "I2C_C_BUF_SCLIN")
	)
	(segment
		(start 13.325348 -91.106498)
		(end 13.325348 -92.291408)
		(width 0.1397)
		(layer "F.Cu")
		(net "I2C_C_BUF_SCLOUT")
	)
	(segment
		(start 13.067538 -93.48343)
		(end 11.51128 -93.48343)
		(width 0.1397)
		(layer "F.Cu")
		(net "I2C_C_BUF_SCLOUT")
	)
	(segment
		(start 10.940288 -92.912438)
		(end 10.940288 -91.57335)
		(width 0.1397)
		(layer "F.Cu")
		(net "I2C_C_BUF_SCLOUT")
	)
	(segment
		(start 13.325348 -93.22562)
		(end 13.067538 -93.48343)
		(width 0.1397)
		(layer "F.Cu")
		(net "I2C_C_BUF_SCLOUT")
	)
	(segment
		(start 13.38707 -90.38463)
		(end 13.38707 -91.044776)
		(width 0.1397)
		(layer "F.Cu")
		(net "I2C_C_BUF_SCLOUT")
	)
	(segment
		(start 13.38707 -91.044776)
		(end 13.325348 -91.106498)
		(width 0.1397)
		(layer "F.Cu")
		(net "I2C_C_BUF_SCLOUT")
	)
	(segment
		(start 13.325348 -92.291408)
		(end 13.325348 -93.22562)
		(width 0.1397)
		(layer "F.Cu")
		(net "I2C_C_BUF_SCLOUT")
	)
	(segment
		(start 11.51128 -93.48343)
		(end 10.940288 -92.912438)
		(width 0.1397)
		(layer "F.Cu")
		(net "I2C_C_BUF_SCLOUT")
	)
	(via
		(at 10.940288 -91.57335)
		(size 0.7112)
		(drill 0.3556)
		(layers "F.Cu" "B.Cu")
		(net "I2C_C_BUF_SCLOUT")
	)
	(segment
		(start 11.536426 -84.935822)
		(end 28.67787 -84.935822)
		(width 0.1397)
		(layer "F.Cu")
		(net "PWM_EXP_B_OUT")
	)
	(segment
		(start 152.580086 -62.079886)
		(end 153.543 -63.0428)
		(width 0.1397)
		(layer "F.Cu")
		(net "PWM_EXP_B_OUT")
	)
	(segment
		(start 152.908 -66.802)
		(end 143.637 -66.802)
		(width 0.1397)
		(layer "F.Cu")
		(net "PWM_EXP_B_OUT")
	)
	(segment
		(start 153.543 -66.167)
		(end 152.908 -66.802)
		(width 0.1397)
		(layer "F.Cu")
		(net "PWM_EXP_B_OUT")
	)
	(segment
		(start 31.922466 -81.691226)
		(end 111.65459 -81.691226)
		(width 0.1397)
		(layer "F.Cu")
		(net "PWM_EXP_B_OUT")
	)
	(segment
		(start 141.057884 -64.222884)
		(end 136.866884 -64.222884)
		(width 0.1397)
		(layer "F.Cu")
		(net "PWM_EXP_B_OUT")
	)
	(segment
		(start 10.636504 -85.835744)
		(end 11.536426 -84.935822)
		(width 0.1397)
		(layer "F.Cu")
		(net "PWM_EXP_B_OUT")
	)
	(segment
		(start 153.543 -63.0428)
		(end 153.543 -66.167)
		(width 0.1397)
		(layer "F.Cu")
		(net "PWM_EXP_B_OUT")
	)
	(segment
		(start 143.637 -66.802)
		(end 141.057884 -64.222884)
		(width 0.1397)
		(layer "F.Cu")
		(net "PWM_EXP_B_OUT")
	)
	(segment
		(start 119.398542 -81.691226)
		(end 111.65459 -81.691226)
		(width 0.1397)
		(layer "F.Cu")
		(net "PWM_EXP_B_OUT")
	)
	(segment
		(start 136.866884 -64.222884)
		(end 119.398542 -81.691226)
		(width 0.1397)
		(layer "F.Cu")
		(net "PWM_EXP_B_OUT")
	)
	(segment
		(start 9.816592 -85.835744)
		(end 10.636504 -85.835744)
		(width 0.1397)
		(layer "F.Cu")
		(net "PWM_EXP_B_OUT")
	)
	(segment
		(start 28.67787 -84.935822)
		(end 31.922466 -81.691226)
		(width 0.1397)
		(layer "F.Cu")
		(net "PWM_EXP_B_OUT")
	)
	(via
		(at 111.65459 -81.691226)
		(size 0.7112)
		(drill 0.3556)
		(layers "F.Cu" "B.Cu")
		(net "PWM_EXP_B_OUT")
	)
	(segment
		(start 12.675108 -97.478342)
		(end 12.409932 -97.743518)
		(width 0.3556)
		(layer "F.Cu")
		(net "P3V3")
	)
	(segment
		(start 15.253208 -99.248468)
		(end 15.253208 -100.247196)
		(width 0.508)
		(layer "F.Cu")
		(net "P3V3")
	)
	(segment
		(start 132.7785 -82.804)
		(end 132.7785 -82.9945)
		(width 0.508)
		(layer "F.Cu")
		(net "P3V3")
	)
	(segment
		(start 138.176 -79.756)
		(end 138.1506 -79.756)
		(width 0.508)
		(layer "F.Cu")
		(net "P3V3")
	)
	(segment
		(start 12.409932 -97.743518)
		(end 11.634978 -98.518472)
		(width 0.508)
		(layer "F.Cu")
		(net "P3V3")
	)
	(segment
		(start 11.634978 -98.518472)
		(end 11.544808 -98.428302)
		(width 0.508)
		(layer "F.Cu")
		(net "P3V3")
	)
	(segment
		(start 136.652 -75.3745)
		(end 136.652 -76.454)
		(width 0.508)
		(layer "F.Cu")
		(net "P3V3")
	)
	(segment
		(start 12.977876 -99.25685)
		(end 12.977876 -100.197412)
		(width 0.508)
		(layer "F.Cu")
		(net "P3V3")
	)
	(segment
		(start 155.650692 -103.844344)
		(end 155.650692 -104.902)
		(width 0.762)
		(layer "F.Cu")
		(net "P3V3")
	)
	(segment
		(start 132.207 -83.566)
		(end 132.207 -84.074)
		(width 0.508)
		(layer "F.Cu")
		(net "P3V3")
	)
	(segment
		(start 132.7785 -82.9945)
		(end 132.207 -83.566)
		(width 0.508)
		(layer "F.Cu")
		(net "P3V3")
	)
	(segment
		(start 10.492486 -98.428302)
		(end 9.782302 -98.428302)
		(width 0.508)
		(layer "F.Cu")
		(net "P3V3")
	)
	(segment
		(start 138.176 -77.978)
		(end 138.176 -79.756)
		(width 0.508)
		(layer "F.Cu")
		(net "P3V3")
	)
	(segment
		(start 14.059408 -99.269296)
		(end 14.059408 -100.247196)
		(width 0.508)
		(layer "F.Cu")
		(net "P3V3")
	)
	(segment
		(start 136.652 -76.454)
		(end 138.176 -77.978)
		(width 0.508)
		(layer "F.Cu")
		(net "P3V3")
	)
	(segment
		(start 11.544808 -98.428302)
		(end 10.492486 -98.428302)
		(width 0.508)
		(layer "F.Cu")
		(net "P3V3")
	)
	(segment
		(start 12.27455 -89.5096)
		(end 12.27455 -88.522556)
		(width 0.508)
		(layer "F.Cu")
		(net "P3V3")
	)
	(segment
		(start 9.782302 -98.428302)
		(end 9.525 -98.171)
		(width 0.508)
		(layer "F.Cu")
		(net "P3V3")
	)
	(segment
		(start 14.579092 -89.51214)
		(end 14.579092 -88.565228)
		(width 0.508)
		(layer "F.Cu")
		(net "P3V3")
	)
	(segment
		(start 13.38707 -89.49563)
		(end 13.38707 -88.551004)
		(width 0.508)
		(layer "F.Cu")
		(net "P3V3")
	)
	(segment
		(start 12.675108 -96.431608)
		(end 12.675108 -97.478342)
		(width 0.3556)
		(layer "F.Cu")
		(net "P3V3")
	)
	(via
		(at 152.4 -86.868)
		(size 0.7112)
		(drill 0.4064)
		(layers "F.Cu" "B.Cu")
		(net "P3V3")
	)
	(via
		(at 132.207 -84.074)
		(size 0.7112)
		(drill 0.4064)
		(layers "F.Cu" "B.Cu")
		(net "P3V3")
	)
	(via
		(at 5.181092 -78.723744)
		(size 0.7112)
		(drill 0.3556)
		(layers "F.Cu" "B.Cu")
		(net "P3V3")
	)
	(via
		(at 152.4 -85.725)
		(size 0.7112)
		(drill 0.4064)
		(layers "F.Cu" "B.Cu")
		(net "P3V3")
	)
	(via
		(at 151.257 -86.868)
		(size 0.7112)
		(drill 0.4064)
		(layers "F.Cu" "B.Cu")
		(net "P3V3")
	)
	(via
		(at 151.257 -85.725)
		(size 0.7112)
		(drill 0.4064)
		(layers "F.Cu" "B.Cu")
		(net "P3V3")
	)
	(via
		(at 155.650692 -104.902)
		(size 0.7112)
		(drill 0.4064)
		(layers "F.Cu" "B.Cu")
		(net "P3V3")
	)
	(via
		(at 12.547092 -82.914744)
		(size 0.7112)
		(drill 0.3556)
		(layers "F.Cu" "B.Cu")
		(net "P3V3")
	)
	(via
		(at 9.525 -98.171)
		(size 0.7112)
		(drill 0.4064)
		(layers "F.Cu" "B.Cu")
		(net "P3V3")
	)
	(via
		(at 153.771092 -103.996744)
		(size 0.7112)
		(drill 0.3556)
		(layers "F.Cu" "B.Cu")
		(net "P3V3")
	)
	(via
		(at 14.579092 -88.565228)
		(size 0.7112)
		(drill 0.4064)
		(layers "F.Cu" "B.Cu")
		(net "P3V3")
	)
	(via
		(at 12.27455 -88.522556)
		(size 0.7112)
		(drill 0.4064)
		(layers "F.Cu" "B.Cu")
		(net "P3V3")
	)
	(via
		(at 15.253208 -100.247196)
		(size 0.7112)
		(drill 0.4064)
		(layers "F.Cu" "B.Cu")
		(net "P3V3")
	)
	(via
		(at 12.977876 -100.197412)
		(size 0.7112)
		(drill 0.4064)
		(layers "F.Cu" "B.Cu")
		(net "P3V3")
	)
	(via
		(at 14.059408 -100.247196)
		(size 0.7112)
		(drill 0.4064)
		(layers "F.Cu" "B.Cu")
		(net "P3V3")
	)
	(via
		(at 147.193 -84.709)
		(size 0.7112)
		(drill 0.3556)
		(layers "F.Cu" "B.Cu")
		(net "P3V3")
	)
	(via
		(at 13.563092 -98.789744)
		(size 0.7112)
		(drill 0.3556)
		(layers "F.Cu" "B.Cu")
		(net "P3V3")
	)
	(via
		(at 138.1506 -79.756)
		(size 0.7112)
		(drill 0.4064)
		(layers "F.Cu" "B.Cu")
		(net "P3V3")
	)
	(via
		(at 13.38707 -88.551004)
		(size 0.7112)
		(drill 0.4064)
		(layers "F.Cu" "B.Cu")
		(net "P3V3")
	)
	(segment
		(start 150.6855 -66.3575)
		(end 144.018 -66.3575)
		(width 0.1397)
		(layer "F.Cu")
		(net "PWM_EXP_A_OUT")
	)
	(segment
		(start 144.018 -66.3575)
		(end 141.438884 -63.778384)
		(width 0.1397)
		(layer "F.Cu")
		(net "PWM_EXP_A_OUT")
	)
	(segment
		(start 28.49372 -84.491322)
		(end 31.846266 -81.138776)
		(width 0.1397)
		(layer "F.Cu")
		(net "PWM_EXP_A_OUT")
	)
	(segment
		(start 11.351514 -84.491322)
		(end 28.49372 -84.491322)
		(width 0.1397)
		(layer "F.Cu")
		(net "PWM_EXP_A_OUT")
	)
	(segment
		(start 141.438884 -63.778384)
		(end 136.682734 -63.778384)
		(width 0.1397)
		(layer "F.Cu")
		(net "PWM_EXP_A_OUT")
	)
	(segment
		(start 119.322342 -81.138776)
		(end 44.897548 -81.138776)
		(width 0.1397)
		(layer "F.Cu")
		(net "PWM_EXP_A_OUT")
	)
	(segment
		(start 11.150092 -84.692744)
		(end 11.351514 -84.491322)
		(width 0.1397)
		(layer "F.Cu")
		(net "PWM_EXP_A_OUT")
	)
	(segment
		(start 151.511 -55.9308)
		(end 151.511 -65.532)
		(width 0.1397)
		(layer "F.Cu")
		(net "PWM_EXP_A_OUT")
	)
	(segment
		(start 151.511 -65.532)
		(end 150.6855 -66.3575)
		(width 0.1397)
		(layer "F.Cu")
		(net "PWM_EXP_A_OUT")
	)
	(segment
		(start 150.040086 -54.459886)
		(end 151.511 -55.9308)
		(width 0.1397)
		(layer "F.Cu")
		(net "PWM_EXP_A_OUT")
	)
	(segment
		(start 31.846266 -81.138776)
		(end 44.897548 -81.138776)
		(width 0.1397)
		(layer "F.Cu")
		(net "PWM_EXP_A_OUT")
	)
	(segment
		(start 136.682734 -63.778384)
		(end 119.322342 -81.138776)
		(width 0.1397)
		(layer "F.Cu")
		(net "PWM_EXP_A_OUT")
	)
	(segment
		(start 9.816592 -84.692744)
		(end 11.150092 -84.692744)
		(width 0.1397)
		(layer "F.Cu")
		(net "PWM_EXP_A_OUT")
	)
	(via
		(at 44.897548 -81.138776)
		(size 0.7112)
		(drill 0.3556)
		(layers "F.Cu" "B.Cu")
		(net "PWM_EXP_A_OUT")
	)
	(segment
		(start 144.960086 -59.539886)
		(end 144.240758 -60.259214)
		(width 0.1397)
		(layer "F.Cu")
		(net "SD_LATCH_RELEASE")
	)
	(segment
		(start 24.110696 -81.454498)
		(end 25.215088 -81.454498)
		(width 0.1397)
		(layer "F.Cu")
		(net "SD_LATCH_RELEASE")
	)
	(segment
		(start -1.143 -83.693)
		(end 0.993394 -83.693)
		(width 0.1397)
		(layer "F.Cu")
		(net "SD_LATCH_RELEASE")
	)
	(segment
		(start -6.99897 -84.379308)
		(end -1.829308 -84.379308)
		(width 0.1397)
		(layer "F.Cu")
		(net "SD_LATCH_RELEASE")
	)
	(segment
		(start 25.215088 -81.454498)
		(end 28.84551 -77.824076)
		(width 0.1397)
		(layer "F.Cu")
		(net "SD_LATCH_RELEASE")
	)
	(segment
		(start 24.110442 -81.454244)
		(end 24.110696 -81.454498)
		(width 0.1397)
		(layer "F.Cu")
		(net "SD_LATCH_RELEASE")
	)
	(segment
		(start 144.240758 -60.259214)
		(end 136.430004 -60.259214)
		(width 0.1397)
		(layer "F.Cu")
		(net "SD_LATCH_RELEASE")
	)
	(segment
		(start 118.865142 -77.824076)
		(end 101.996494 -77.824076)
		(width 0.1397)
		(layer "F.Cu")
		(net "SD_LATCH_RELEASE")
	)
	(segment
		(start 28.84551 -77.824076)
		(end 101.996494 -77.824076)
		(width 0.1397)
		(layer "F.Cu")
		(net "SD_LATCH_RELEASE")
	)
	(segment
		(start 0.993394 -83.693)
		(end 3.23215 -81.454244)
		(width 0.1397)
		(layer "F.Cu")
		(net "SD_LATCH_RELEASE")
	)
	(segment
		(start 136.430004 -60.259214)
		(end 118.865142 -77.824076)
		(width 0.1397)
		(layer "F.Cu")
		(net "SD_LATCH_RELEASE")
	)
	(segment
		(start -1.829308 -84.379308)
		(end -1.143 -83.693)
		(width 0.1397)
		(layer "F.Cu")
		(net "SD_LATCH_RELEASE")
	)
	(segment
		(start 3.23215 -81.454244)
		(end 24.110442 -81.454244)
		(width 0.1397)
		(layer "F.Cu")
		(net "SD_LATCH_RELEASE")
	)
	(via
		(at 101.996494 -77.824076)
		(size 0.7112)
		(drill 0.3556)
		(layers "F.Cu" "B.Cu")
		(net "SD_LATCH_RELEASE")
	)
	(segment
		(start 118.941342 -78.376526)
		(end 111.609378 -78.376526)
		(width 0.1397)
		(layer "F.Cu")
		(net "FCB_HW_REV")
	)
	(segment
		(start 0.272034 -84.201)
		(end 1.114044 -84.201)
		(width 0.1397)
		(layer "F.Cu")
		(net "FCB_HW_REV")
	)
	(segment
		(start -6.99897 -85.649308)
		(end -3.480308 -85.649308)
		(width 0.1397)
		(layer "F.Cu")
		(net "FCB_HW_REV")
	)
	(segment
		(start 145.880836 -60.240164)
		(end 145.417286 -60.703714)
		(width 0.1397)
		(layer "F.Cu")
		(net "FCB_HW_REV")
	)
	(segment
		(start 145.880836 -58.498486)
		(end 145.880836 -60.240164)
		(width 0.1397)
		(layer "F.Cu")
		(net "FCB_HW_REV")
	)
	(segment
		(start 144.960086 -57.577736)
		(end 145.880836 -58.498486)
		(width 0.1397)
		(layer "F.Cu")
		(net "FCB_HW_REV")
	)
	(segment
		(start -0.362966 -84.836)
		(end 0.272034 -84.201)
		(width 0.1397)
		(layer "F.Cu")
		(net "FCB_HW_REV")
	)
	(segment
		(start 1.114044 -84.201)
		(end 3.4163 -81.898744)
		(width 0.1397)
		(layer "F.Cu")
		(net "FCB_HW_REV")
	)
	(segment
		(start 145.417286 -60.703714)
		(end 136.614154 -60.703714)
		(width 0.1397)
		(layer "F.Cu")
		(net "FCB_HW_REV")
	)
	(segment
		(start 3.4163 -81.898744)
		(end 23.926292 -81.898744)
		(width 0.1397)
		(layer "F.Cu")
		(net "FCB_HW_REV")
	)
	(segment
		(start 28.92171 -78.376526)
		(end 111.609378 -78.376526)
		(width 0.1397)
		(layer "F.Cu")
		(net "FCB_HW_REV")
	)
	(segment
		(start 144.960086 -56.999886)
		(end 144.960086 -57.577736)
		(width 0.1397)
		(layer "F.Cu")
		(net "FCB_HW_REV")
	)
	(segment
		(start 23.926546 -81.898998)
		(end 25.399238 -81.898998)
		(width 0.1397)
		(layer "F.Cu")
		(net "FCB_HW_REV")
	)
	(segment
		(start -3.480308 -85.649308)
		(end -2.667 -84.836)
		(width 0.1397)
		(layer "F.Cu")
		(net "FCB_HW_REV")
	)
	(segment
		(start -2.667 -84.836)
		(end -0.362966 -84.836)
		(width 0.1397)
		(layer "F.Cu")
		(net "FCB_HW_REV")
	)
	(segment
		(start 136.614154 -60.703714)
		(end 118.941342 -78.376526)
		(width 0.1397)
		(layer "F.Cu")
		(net "FCB_HW_REV")
	)
	(segment
		(start 23.926292 -81.898744)
		(end 23.926546 -81.898998)
		(width 0.1397)
		(layer "F.Cu")
		(net "FCB_HW_REV")
	)
	(segment
		(start 25.399238 -81.898998)
		(end 28.92171 -78.376526)
		(width 0.1397)
		(layer "F.Cu")
		(net "FCB_HW_REV")
	)
	(via
		(at 111.609378 -78.376526)
		(size 0.7112)
		(drill 0.3556)
		(layers "F.Cu" "B.Cu")
		(net "FCB_HW_REV")
	)
	(segment
		(start -1.391158 -86.493096)
		(end 0.392938 -84.709)
		(width 0.1397)
		(layer "F.Cu")
		(net "TRAY_ID")
	)
	(segment
		(start 146.05 -55.5498)
		(end 146.05 -58.039)
		(width 0.1397)
		(layer "F.Cu")
		(net "TRAY_ID")
	)
	(segment
		(start 28.99791 -78.928976)
		(end 78.99146 -78.928976)
		(width 0.1397)
		(layer "F.Cu")
		(net "TRAY_ID")
	)
	(segment
		(start -3.510788 -86.493096)
		(end -1.391158 -86.493096)
		(width 0.1397)
		(layer "F.Cu")
		(net "TRAY_ID")
	)
	(segment
		(start 25.583642 -82.343498)
		(end 25.844246 -82.082894)
		(width 0.1397)
		(layer "F.Cu")
		(net "TRAY_ID")
	)
	(segment
		(start 144.960086 -54.459886)
		(end 146.05 -55.5498)
		(width 0.1397)
		(layer "F.Cu")
		(net "TRAY_ID")
	)
	(segment
		(start 136.798304 -61.148214)
		(end 119.017542 -78.928976)
		(width 0.1397)
		(layer "F.Cu")
		(net "TRAY_ID")
	)
	(segment
		(start 146.325336 -58.314336)
		(end 146.325336 -60.557664)
		(width 0.1397)
		(layer "F.Cu")
		(net "TRAY_ID")
	)
	(segment
		(start 146.05 -58.039)
		(end 146.325336 -58.314336)
		(width 0.1397)
		(layer "F.Cu")
		(net "TRAY_ID")
	)
	(segment
		(start 23.742142 -82.343244)
		(end 23.742396 -82.343498)
		(width 0.1397)
		(layer "F.Cu")
		(net "TRAY_ID")
	)
	(segment
		(start 145.233136 -61.148214)
		(end 136.798304 -61.148214)
		(width 0.1397)
		(layer "F.Cu")
		(net "TRAY_ID")
	)
	(segment
		(start 119.017542 -78.928976)
		(end 78.99146 -78.928976)
		(width 0.1397)
		(layer "F.Cu")
		(net "TRAY_ID")
	)
	(segment
		(start 25.844246 -82.08264)
		(end 28.99791 -78.928976)
		(width 0.1397)
		(layer "F.Cu")
		(net "TRAY_ID")
	)
	(segment
		(start 145.23339 -61.148468)
		(end 145.233136 -61.148214)
		(width 0.1397)
		(layer "F.Cu")
		(net "TRAY_ID")
	)
	(segment
		(start 0.392938 -84.709)
		(end 1.234948 -84.709)
		(width 0.1397)
		(layer "F.Cu")
		(net "TRAY_ID")
	)
	(segment
		(start 145.601182 -61.148468)
		(end 145.23339 -61.148468)
		(width 0.1397)
		(layer "F.Cu")
		(net "TRAY_ID")
	)
	(segment
		(start 145.601436 -61.148214)
		(end 145.601182 -61.148468)
		(width 0.1397)
		(layer "F.Cu")
		(net "TRAY_ID")
	)
	(segment
		(start 25.844246 -82.082894)
		(end 25.844246 -82.08264)
		(width 0.1397)
		(layer "F.Cu")
		(net "TRAY_ID")
	)
	(segment
		(start 1.234948 -84.709)
		(end 3.600704 -82.343244)
		(width 0.1397)
		(layer "F.Cu")
		(net "TRAY_ID")
	)
	(segment
		(start 146.325336 -60.557664)
		(end 145.734786 -61.148214)
		(width 0.1397)
		(layer "F.Cu")
		(net "TRAY_ID")
	)
	(segment
		(start 145.734786 -61.148214)
		(end 145.601436 -61.148214)
		(width 0.1397)
		(layer "F.Cu")
		(net "TRAY_ID")
	)
	(segment
		(start 3.600704 -82.343244)
		(end 23.742142 -82.343244)
		(width 0.1397)
		(layer "F.Cu")
		(net "TRAY_ID")
	)
	(segment
		(start -6.99897 -86.919308)
		(end -3.937 -86.919308)
		(width 0.1397)
		(layer "F.Cu")
		(net "TRAY_ID")
	)
	(segment
		(start -3.937 -86.919308)
		(end -3.510788 -86.493096)
		(width 0.1397)
		(layer "F.Cu")
		(net "TRAY_ID")
	)
	(segment
		(start 23.742396 -82.343498)
		(end 25.583642 -82.343498)
		(width 0.1397)
		(layer "F.Cu")
		(net "TRAY_ID")
	)
	(via
		(at 78.99146 -78.928976)
		(size 0.7112)
		(drill 0.3556)
		(layers "F.Cu" "B.Cu")
		(net "TRAY_ID")
	)
	(segment
		(start 24.294846 -81.009998)
		(end 25.030938 -81.009998)
		(width 0.1397)
		(layer "F.Cu")
		(net "PEER_TRAY_PRESENT")
	)
	(segment
		(start 143.51 -53.369972)
		(end 143.51 -59.055)
		(width 0.1397)
		(layer "F.Cu")
		(net "PEER_TRAY_PRESENT")
	)
	(segment
		(start 142.75054 -59.81446)
		(end 137.031476 -59.81446)
		(width 0.1397)
		(layer "F.Cu")
		(net "PEER_TRAY_PRESENT")
	)
	(segment
		(start 0.994918 -83.041744)
		(end 3.026918 -81.009744)
		(width 0.1397)
		(layer "F.Cu")
		(net "PEER_TRAY_PRESENT")
	)
	(segment
		(start 24.294592 -81.009744)
		(end 24.294846 -81.009998)
		(width 0.1397)
		(layer "F.Cu")
		(net "PEER_TRAY_PRESENT")
	)
	(segment
		(start 28.76931 -77.271626)
		(end 34.306002 -77.271626)
		(width 0.1397)
		(layer "F.Cu")
		(net "PEER_TRAY_PRESENT")
	)
	(segment
		(start 25.030938 -81.009998)
		(end 28.76931 -77.271626)
		(width 0.1397)
		(layer "F.Cu")
		(net "PEER_TRAY_PRESENT")
	)
	(segment
		(start 143.51 -59.055)
		(end 142.75054 -59.81446)
		(width 0.1397)
		(layer "F.Cu")
		(net "PEER_TRAY_PRESENT")
	)
	(segment
		(start 144.960086 -51.919886)
		(end 143.51 -53.369972)
		(width 0.1397)
		(layer "F.Cu")
		(net "PEER_TRAY_PRESENT")
	)
	(segment
		(start 118.788942 -77.271626)
		(end 34.306002 -77.271626)
		(width 0.1397)
		(layer "F.Cu")
		(net "PEER_TRAY_PRESENT")
	)
	(segment
		(start 3.026918 -81.009744)
		(end 24.294592 -81.009744)
		(width 0.1397)
		(layer "F.Cu")
		(net "PEER_TRAY_PRESENT")
	)
	(segment
		(start 137.031476 -59.81446)
		(end 137.031222 -59.814714)
		(width 0.1397)
		(layer "F.Cu")
		(net "PEER_TRAY_PRESENT")
	)
	(segment
		(start 0.863092 -83.041744)
		(end 0.994918 -83.041744)
		(width 0.1397)
		(layer "F.Cu")
		(net "PEER_TRAY_PRESENT")
	)
	(segment
		(start 137.031222 -59.814714)
		(end 136.245854 -59.814714)
		(width 0.1397)
		(layer "F.Cu")
		(net "PEER_TRAY_PRESENT")
	)
	(segment
		(start 136.245854 -59.814714)
		(end 118.788942 -77.271626)
		(width 0.1397)
		(layer "F.Cu")
		(net "PEER_TRAY_PRESENT")
	)
	(via
		(at 0.863092 -83.041744)
		(size 0.7112)
		(drill 0.4064)
		(layers "F.Cu" "B.Cu")
		(net "PEER_TRAY_PRESENT")
	)
	(via
		(at 34.306002 -77.271626)
		(size 0.7112)
		(drill 0.3556)
		(layers "F.Cu" "B.Cu")
		(net "PEER_TRAY_PRESENT")
	)
	(segment
		(start 0.127 -83.041744)
		(end -1.761744 -81.153)
		(width 0.1397)
		(layer "B.Cu")
		(net "PEER_TRAY_PRESENT")
	)
	(segment
		(start -3.710686 -81.153)
		(end -4.294378 -80.569308)
		(width 0.1397)
		(layer "B.Cu")
		(net "PEER_TRAY_PRESENT")
	)
	(segment
		(start -1.761744 -81.153)
		(end -3.710686 -81.153)
		(width 0.1397)
		(layer "B.Cu")
		(net "PEER_TRAY_PRESENT")
	)
	(segment
		(start -4.294378 -80.569308)
		(end -6.61797 -80.569308)
		(width 0.1397)
		(layer "B.Cu")
		(net "PEER_TRAY_PRESENT")
	)
	(segment
		(start 0.863092 -83.041744)
		(end 0.127 -83.041744)
		(width 0.1397)
		(layer "B.Cu")
		(net "PEER_TRAY_PRESENT")
	)
	(segment
		(start 7.158228 -96.266762)
		(end 7.677658 -96.266762)
		(width 0.1397)
		(layer "F.Cu")
		(net "I2C_C_SDA")
	)
	(segment
		(start 10.962386 -94.95409)
		(end 11.24458 -94.671896)
		(width 0.1397)
		(layer "F.Cu")
		(net "I2C_C_SDA")
	)
	(segment
		(start 16.469868 -94.671896)
		(end 16.788638 -94.990666)
		(width 0.1397)
		(layer "F.Cu")
		(net "I2C_C_SDA")
	)
	(segment
		(start 8.523732 -95.420688)
		(end 8.523732 -95.029528)
		(width 0.1397)
		(layer "F.Cu")
		(net "I2C_C_SDA")
	)
	(segment
		(start 9.684512 -95.029528)
		(end 10.102596 -94.611444)
		(width 0.1397)
		(layer "F.Cu")
		(net "I2C_C_SDA")
	)
	(segment
		(start 8.523732 -95.029528)
		(end 9.684512 -95.029528)
		(width 0.1397)
		(layer "F.Cu")
		(net "I2C_C_SDA")
	)
	(segment
		(start 10.102596 -94.611444)
		(end 10.61974 -94.611444)
		(width 0.1397)
		(layer "F.Cu")
		(net "I2C_C_SDA")
	)
	(segment
		(start 11.24458 -94.671896)
		(end 16.469868 -94.671896)
		(width 0.1397)
		(layer "F.Cu")
		(net "I2C_C_SDA")
	)
	(segment
		(start 10.61974 -94.611444)
		(end 10.962386 -94.95409)
		(width 0.1397)
		(layer "F.Cu")
		(net "I2C_C_SDA")
	)
	(segment
		(start 7.677658 -96.266762)
		(end 8.523732 -95.420688)
		(width 0.1397)
		(layer "F.Cu")
		(net "I2C_C_SDA")
	)
	(via
		(at 7.158228 -96.266762)
		(size 0.7112)
		(drill 0.3556)
		(layers "F.Cu" "B.Cu")
		(net "I2C_C_SDA")
	)
	(segment
		(start 136.596882 -67.048634)
		(end 137.795 -67.048634)
		(width 0.1397)
		(layer "F.Cu")
		(net "I2C_C_BUF_SCL_CONN")
	)
	(segment
		(start 137.795 -67.048634)
		(end 138.049254 -66.79438)
		(width 0.1397)
		(layer "F.Cu")
		(net "I2C_C_BUF_SCL_CONN")
	)
	(segment
		(start 153.3017 -68.8213)
		(end 141.8463 -68.8213)
		(width 0.1397)
		(layer "F.Cu")
		(net "I2C_C_BUF_SCL_CONN")
	)
	(segment
		(start 139.81938 -66.79438)
		(end 139.297918 -66.79438)
		(width 0.1397)
		(layer "F.Cu")
		(net "I2C_C_BUF_SCL_CONN")
	)
	(segment
		(start 138.049254 -66.79438)
		(end 139.297918 -66.79438)
		(width 0.1397)
		(layer "F.Cu")
		(net "I2C_C_BUF_SCL_CONN")
	)
	(segment
		(start 152.580086 -56.999886)
		(end 154.1907 -58.6105)
		(width 0.1397)
		(layer "F.Cu")
		(net "I2C_C_BUF_SCL_CONN")
	)
	(segment
		(start 154.1907 -67.9323)
		(end 153.3017 -68.8213)
		(width 0.1397)
		(layer "F.Cu")
		(net "I2C_C_BUF_SCL_CONN")
	)
	(segment
		(start 154.1907 -58.6105)
		(end 154.1907 -67.9323)
		(width 0.1397)
		(layer "F.Cu")
		(net "I2C_C_BUF_SCL_CONN")
	)
	(segment
		(start 141.8463 -68.8213)
		(end 139.81938 -66.79438)
		(width 0.1397)
		(layer "F.Cu")
		(net "I2C_C_BUF_SCL_CONN")
	)
	(via
		(at 139.297918 -66.79438)
		(size 0.7112)
		(drill 0.3556)
		(layers "F.Cu" "B.Cu")
		(net "I2C_C_BUF_SCL_CONN")
	)
	(segment
		(start 136.061704 -59.370214)
		(end 118.712742 -76.719176)
		(width 0.1397)
		(layer "F.Cu")
		(net "PEER_1A&2A_HB")
	)
	(segment
		(start 24.478742 -80.565244)
		(end 24.478996 -80.565498)
		(width 0.1397)
		(layer "F.Cu")
		(net "PEER_1A&2A_HB")
	)
	(segment
		(start 142.17904 -59.36996)
		(end 136.847326 -59.36996)
		(width 0.1397)
		(layer "F.Cu")
		(net "PEER_1A&2A_HB")
	)
	(segment
		(start 118.712742 -76.719176)
		(end 49.857406 -76.719176)
		(width 0.1397)
		(layer "F.Cu")
		(net "PEER_1A&2A_HB")
	)
	(segment
		(start 2.842768 -80.565244)
		(end 24.478742 -80.565244)
		(width 0.1397)
		(layer "F.Cu")
		(net "PEER_1A&2A_HB")
	)
	(segment
		(start 136.847072 -59.370214)
		(end 136.061704 -59.370214)
		(width 0.1397)
		(layer "F.Cu")
		(net "PEER_1A&2A_HB")
	)
	(segment
		(start -6.99897 -81.839308)
		(end -3.225292 -81.839308)
		(width 0.1397)
		(layer "F.Cu")
		(net "PEER_1A&2A_HB")
	)
	(segment
		(start 24.846788 -80.565498)
		(end 28.69311 -76.719176)
		(width 0.1397)
		(layer "F.Cu")
		(net "PEER_1A&2A_HB")
	)
	(segment
		(start 142.621 -58.928)
		(end 142.17904 -59.36996)
		(width 0.1397)
		(layer "F.Cu")
		(net "PEER_1A&2A_HB")
	)
	(segment
		(start -3.225292 -81.839308)
		(end -2.79908 -82.26552)
		(width 0.1397)
		(layer "F.Cu")
		(net "PEER_1A&2A_HB")
	)
	(segment
		(start 1.142492 -82.26552)
		(end 2.842768 -80.565244)
		(width 0.1397)
		(layer "F.Cu")
		(net "PEER_1A&2A_HB")
	)
	(segment
		(start 136.847326 -59.36996)
		(end 136.847072 -59.370214)
		(width 0.1397)
		(layer "F.Cu")
		(net "PEER_1A&2A_HB")
	)
	(segment
		(start 24.478996 -80.565498)
		(end 24.846788 -80.565498)
		(width 0.1397)
		(layer "F.Cu")
		(net "PEER_1A&2A_HB")
	)
	(segment
		(start 28.69311 -76.719176)
		(end 49.857406 -76.719176)
		(width 0.1397)
		(layer "F.Cu")
		(net "PEER_1A&2A_HB")
	)
	(segment
		(start -2.79908 -82.26552)
		(end 1.142492 -82.26552)
		(width 0.1397)
		(layer "F.Cu")
		(net "PEER_1A&2A_HB")
	)
	(via
		(at 49.857406 -76.719176)
		(size 0.7112)
		(drill 0.3556)
		(layers "F.Cu" "B.Cu")
		(net "PEER_1A&2A_HB")
	)
	(via
		(at 142.621 -58.928)
		(size 0.7112)
		(drill 0.4064)
		(layers "F.Cu" "B.Cu")
		(net "PEER_1A&2A_HB")
	)
	(segment
		(start 142.621 -59.309)
		(end 142.621 -58.928)
		(width 0.1397)
		(layer "B.Cu")
		(net "PEER_1A&2A_HB")
	)
	(segment
		(start 143.8275 -60.5155)
		(end 142.621 -59.309)
		(width 0.1397)
		(layer "B.Cu")
		(net "PEER_1A&2A_HB")
	)
	(segment
		(start 146.524472 -60.5155)
		(end 143.8275 -60.5155)
		(width 0.1397)
		(layer "B.Cu")
		(net "PEER_1A&2A_HB")
	)
	(segment
		(start 147.500086 -59.539886)
		(end 146.524472 -60.5155)
		(width 0.1397)
		(layer "B.Cu")
		(net "PEER_1A&2A_HB")
	)
	(segment
		(start 8.523986 -93.708982)
		(end 8.523732 -93.708728)
		(width 0.1397)
		(layer "F.Cu")
		(net "I2C_C_SCL")
	)
	(segment
		(start 7.677658 -92.471494)
		(end 7.158228 -92.471494)
		(width 0.1397)
		(layer "F.Cu")
		(net "I2C_C_SCL")
	)
	(segment
		(start 16.518636 -94.102936)
		(end 11.241786 -94.102936)
		(width 0.1397)
		(layer "F.Cu")
		(net "I2C_C_SCL")
	)
	(segment
		(start 10.940288 -93.801438)
		(end 10.650982 -94.090744)
		(width 0.1397)
		(layer "F.Cu")
		(net "I2C_C_SCL")
	)
	(segment
		(start 10.650982 -94.090744)
		(end 10.061448 -94.090744)
		(width 0.1397)
		(layer "F.Cu")
		(net "I2C_C_SCL")
	)
	(segment
		(start 10.061448 -94.090744)
		(end 9.679686 -93.708982)
		(width 0.1397)
		(layer "F.Cu")
		(net "I2C_C_SCL")
	)
	(segment
		(start 11.241786 -94.102936)
		(end 10.940288 -93.801438)
		(width 0.1397)
		(layer "F.Cu")
		(net "I2C_C_SCL")
	)
	(segment
		(start 16.776192 -93.84538)
		(end 16.518636 -94.102936)
		(width 0.1397)
		(layer "F.Cu")
		(net "I2C_C_SCL")
	)
	(segment
		(start 8.523732 -93.708728)
		(end 8.523732 -93.317568)
		(width 0.1397)
		(layer "F.Cu")
		(net "I2C_C_SCL")
	)
	(segment
		(start 8.523732 -93.317568)
		(end 7.677658 -92.471494)
		(width 0.1397)
		(layer "F.Cu")
		(net "I2C_C_SCL")
	)
	(segment
		(start 9.679686 -93.708982)
		(end 8.523986 -93.708982)
		(width 0.1397)
		(layer "F.Cu")
		(net "I2C_C_SCL")
	)
	(via
		(at 7.158228 -92.471494)
		(size 0.7112)
		(drill 0.3556)
		(layers "F.Cu" "B.Cu")
		(net "I2C_C_SCL")
	)
	(segment
		(start 152.580086 -51.919886)
		(end 154.7114 -54.0512)
		(width 0.1397)
		(layer "F.Cu")
		(net "I2C_C_BUF_SDA_CONN")
	)
	(segment
		(start 141.605 -69.342)
		(end 140.78458 -68.52158)
		(width 0.1397)
		(layer "F.Cu")
		(net "I2C_C_BUF_SDA_CONN")
	)
	(segment
		(start 154.7114 -54.0512)
		(end 154.7114 -68.1736)
		(width 0.1397)
		(layer "F.Cu")
		(net "I2C_C_BUF_SDA_CONN")
	)
	(segment
		(start 140.78458 -68.52158)
		(end 139.297918 -68.52158)
		(width 0.1397)
		(layer "F.Cu")
		(net "I2C_C_BUF_SDA_CONN")
	)
	(segment
		(start 154.7114 -68.1736)
		(end 153.543 -69.342)
		(width 0.1397)
		(layer "F.Cu")
		(net "I2C_C_BUF_SDA_CONN")
	)
	(segment
		(start 153.543 -69.342)
		(end 141.605 -69.342)
		(width 0.1397)
		(layer "F.Cu")
		(net "I2C_C_BUF_SDA_CONN")
	)
	(segment
		(start 136.596882 -68.318634)
		(end 137.795 -68.318634)
		(width 0.1397)
		(layer "F.Cu")
		(net "I2C_C_BUF_SDA_CONN")
	)
	(segment
		(start 137.997946 -68.52158)
		(end 139.297918 -68.52158)
		(width 0.1397)
		(layer "F.Cu")
		(net "I2C_C_BUF_SDA_CONN")
	)
	(segment
		(start 137.795 -68.318634)
		(end 137.997946 -68.52158)
		(width 0.1397)
		(layer "F.Cu")
		(net "I2C_C_BUF_SDA_CONN")
	)
	(via
		(at 139.297918 -68.52158)
		(size 0.7112)
		(drill 0.3556)
		(layers "F.Cu" "B.Cu")
		(net "I2C_C_BUF_SDA_CONN")
	)
	(segment
		(start 141.35354 -58.92546)
		(end 135.877808 -58.92546)
		(width 0.1397)
		(layer "F.Cu")
		(net "PEER_1B&2B_HB")
	)
	(segment
		(start 141.478 -58.801)
		(end 141.35354 -58.92546)
		(width 0.1397)
		(layer "F.Cu")
		(net "PEER_1B&2B_HB")
	)
	(segment
		(start 135.877808 -58.92546)
		(end 118.636542 -76.166726)
		(width 0.1397)
		(layer "F.Cu")
		(net "PEER_1B&2B_HB")
	)
	(segment
		(start 24.662638 -80.120744)
		(end 28.616656 -76.166726)
		(width 0.1397)
		(layer "F.Cu")
		(net "PEER_1B&2B_HB")
	)
	(segment
		(start 2.658618 -80.120744)
		(end 24.662638 -80.120744)
		(width 0.1397)
		(layer "F.Cu")
		(net "PEER_1B&2B_HB")
	)
	(segment
		(start -6.99897 -80.569308)
		(end -3.866642 -80.569308)
		(width 0.1397)
		(layer "F.Cu")
		(net "PEER_1B&2B_HB")
	)
	(segment
		(start 118.636542 -76.166726)
		(end 117.667786 -76.166726)
		(width 0.1397)
		(layer "F.Cu")
		(net "PEER_1B&2B_HB")
	)
	(segment
		(start 0.958342 -81.82102)
		(end 2.658618 -80.120744)
		(width 0.1397)
		(layer "F.Cu")
		(net "PEER_1B&2B_HB")
	)
	(segment
		(start -3.866642 -80.569308)
		(end -2.61493 -81.82102)
		(width 0.1397)
		(layer "F.Cu")
		(net "PEER_1B&2B_HB")
	)
	(segment
		(start 28.616656 -76.166726)
		(end 117.667786 -76.166726)
		(width 0.1397)
		(layer "F.Cu")
		(net "PEER_1B&2B_HB")
	)
	(segment
		(start -2.61493 -81.82102)
		(end 0.958342 -81.82102)
		(width 0.1397)
		(layer "F.Cu")
		(net "PEER_1B&2B_HB")
	)
	(via
		(at 141.478 -58.801)
		(size 0.7112)
		(drill 0.4064)
		(layers "F.Cu" "B.Cu")
		(net "PEER_1B&2B_HB")
	)
	(via
		(at 117.667786 -76.166726)
		(size 0.7112)
		(drill 0.3556)
		(layers "F.Cu" "B.Cu")
		(net "PEER_1B&2B_HB")
	)
	(segment
		(start 146.3802 -60.96)
		(end 143.637 -60.96)
		(width 0.1397)
		(layer "B.Cu")
		(net "PEER_1B&2B_HB")
	)
	(segment
		(start 147.500086 -62.079886)
		(end 146.3802 -60.96)
		(width 0.1397)
		(layer "B.Cu")
		(net "PEER_1B&2B_HB")
	)
	(segment
		(start 143.637 -60.96)
		(end 141.478 -58.801)
		(width 0.1397)
		(layer "B.Cu")
		(net "PEER_1B&2B_HB")
	)
	(segment
		(start 148.6662 -58.166)
		(end 150.241 -58.166)
		(width 0.1397)
		(layer "F.Cu")
		(net "SELF_1A&2A_HB")
	)
	(segment
		(start 26.136092 -83.676998)
		(end 29.226764 -80.586326)
		(width 0.1397)
		(layer "F.Cu")
		(net "SELF_1A&2A_HB")
	)
	(segment
		(start -6.99897 -89.459308)
		(end -4.064 -89.459308)
		(width 0.1397)
		(layer "F.Cu")
		(net "SELF_1A&2A_HB")
	)
	(segment
		(start 29.226764 -80.586326)
		(end 67.22872 -80.586326)
		(width 0.1397)
		(layer "F.Cu")
		(net "SELF_1A&2A_HB")
	)
	(segment
		(start -1.986788 -87.382096)
		(end -1.022096 -87.382096)
		(width 0.1397)
		(layer "F.Cu")
		(net "SELF_1A&2A_HB")
	)
	(segment
		(start 2.553462 -85.725)
		(end 4.601718 -83.676744)
		(width 0.1397)
		(layer "F.Cu")
		(net "SELF_1A&2A_HB")
	)
	(segment
		(start 143.383 -64.262)
		(end 141.602714 -62.481714)
		(width 0.1397)
		(layer "F.Cu")
		(net "SELF_1A&2A_HB")
	)
	(segment
		(start 151.0665 -63.5635)
		(end 150.368 -64.262)
		(width 0.1397)
		(layer "F.Cu")
		(net "SELF_1A&2A_HB")
	)
	(segment
		(start 151.0665 -58.9915)
		(end 151.0665 -63.5635)
		(width 0.1397)
		(layer "F.Cu")
		(net "SELF_1A&2A_HB")
	)
	(segment
		(start 150.241 -58.166)
		(end 151.0665 -58.9915)
		(width 0.1397)
		(layer "F.Cu")
		(net "SELF_1A&2A_HB")
	)
	(segment
		(start 119.246142 -80.586326)
		(end 67.22872 -80.586326)
		(width 0.1397)
		(layer "F.Cu")
		(net "SELF_1A&2A_HB")
	)
	(segment
		(start -1.022096 -87.382096)
		(end 0.635 -85.725)
		(width 0.1397)
		(layer "F.Cu")
		(net "SELF_1A&2A_HB")
	)
	(segment
		(start 23.189692 -83.676744)
		(end 23.189946 -83.676998)
		(width 0.1397)
		(layer "F.Cu")
		(net "SELF_1A&2A_HB")
	)
	(segment
		(start 137.350754 -62.481714)
		(end 119.246142 -80.586326)
		(width 0.1397)
		(layer "F.Cu")
		(net "SELF_1A&2A_HB")
	)
	(segment
		(start 147.500086 -56.999886)
		(end 148.6662 -58.166)
		(width 0.1397)
		(layer "F.Cu")
		(net "SELF_1A&2A_HB")
	)
	(segment
		(start 0.635 -85.725)
		(end 2.553462 -85.725)
		(width 0.1397)
		(layer "F.Cu")
		(net "SELF_1A&2A_HB")
	)
	(segment
		(start 23.189946 -83.676998)
		(end 26.136092 -83.676998)
		(width 0.1397)
		(layer "F.Cu")
		(net "SELF_1A&2A_HB")
	)
	(segment
		(start -4.064 -89.459308)
		(end -1.986788 -87.382096)
		(width 0.1397)
		(layer "F.Cu")
		(net "SELF_1A&2A_HB")
	)
	(segment
		(start 4.601718 -83.676744)
		(end 23.189692 -83.676744)
		(width 0.1397)
		(layer "F.Cu")
		(net "SELF_1A&2A_HB")
	)
	(segment
		(start 141.602714 -62.481714)
		(end 137.350754 -62.481714)
		(width 0.1397)
		(layer "F.Cu")
		(net "SELF_1A&2A_HB")
	)
	(segment
		(start 150.368 -64.262)
		(end 143.383 -64.262)
		(width 0.1397)
		(layer "F.Cu")
		(net "SELF_1A&2A_HB")
	)
	(via
		(at 67.22872 -80.586326)
		(size 0.7112)
		(drill 0.3556)
		(layers "F.Cu" "B.Cu")
		(net "SELF_1A&2A_HB")
	)
	(segment
		(start -1.206754 -86.937596)
		(end 0.513842 -85.217)
		(width 0.1397)
		(layer "F.Cu")
		(net "SELF_1B&2B_HB")
	)
	(segment
		(start -4.191 -88.189308)
		(end -2.939288 -86.937596)
		(width 0.1397)
		(layer "F.Cu")
		(net "SELF_1B&2B_HB")
	)
	(segment
		(start 137.166604 -62.037214)
		(end 119.169942 -80.033876)
		(width 0.1397)
		(layer "F.Cu")
		(net "SELF_1B&2B_HB")
	)
	(segment
		(start 148.2725 -63.8175)
		(end 143.56715 -63.8175)
		(width 0.1397)
		(layer "F.Cu")
		(net "SELF_1B&2B_HB")
	)
	(segment
		(start 141.786864 -62.037214)
		(end 137.166604 -62.037214)
		(width 0.1397)
		(layer "F.Cu")
		(net "SELF_1B&2B_HB")
	)
	(segment
		(start 143.56715 -63.8175)
		(end 141.786864 -62.037214)
		(width 0.1397)
		(layer "F.Cu")
		(net "SELF_1B&2B_HB")
	)
	(segment
		(start 119.169942 -80.033876)
		(end 58.093864 -80.033876)
		(width 0.1397)
		(layer "F.Cu")
		(net "SELF_1B&2B_HB")
	)
	(segment
		(start -6.99897 -88.189308)
		(end -4.191 -88.189308)
		(width 0.1397)
		(layer "F.Cu")
		(net "SELF_1B&2B_HB")
	)
	(segment
		(start 150.040086 -59.539886)
		(end 148.844 -60.735972)
		(width 0.1397)
		(layer "F.Cu")
		(net "SELF_1B&2B_HB")
	)
	(segment
		(start -2.939288 -86.937596)
		(end -1.206754 -86.937596)
		(width 0.1397)
		(layer "F.Cu")
		(net "SELF_1B&2B_HB")
	)
	(segment
		(start 23.373842 -83.232244)
		(end 23.374096 -83.232498)
		(width 0.1397)
		(layer "F.Cu")
		(net "SELF_1B&2B_HB")
	)
	(segment
		(start 23.374096 -83.232498)
		(end 25.951942 -83.232498)
		(width 0.1397)
		(layer "F.Cu")
		(net "SELF_1B&2B_HB")
	)
	(segment
		(start 29.150564 -80.033876)
		(end 58.093864 -80.033876)
		(width 0.1397)
		(layer "F.Cu")
		(net "SELF_1B&2B_HB")
	)
	(segment
		(start 148.844 -63.246)
		(end 148.2725 -63.8175)
		(width 0.1397)
		(layer "F.Cu")
		(net "SELF_1B&2B_HB")
	)
	(segment
		(start 148.844 -60.735972)
		(end 148.844 -63.246)
		(width 0.1397)
		(layer "F.Cu")
		(net "SELF_1B&2B_HB")
	)
	(segment
		(start 4.417314 -83.232244)
		(end 23.373842 -83.232244)
		(width 0.1397)
		(layer "F.Cu")
		(net "SELF_1B&2B_HB")
	)
	(segment
		(start 0.513842 -85.217)
		(end 2.432558 -85.217)
		(width 0.1397)
		(layer "F.Cu")
		(net "SELF_1B&2B_HB")
	)
	(segment
		(start 25.951942 -83.232498)
		(end 29.150564 -80.033876)
		(width 0.1397)
		(layer "F.Cu")
		(net "SELF_1B&2B_HB")
	)
	(segment
		(start 2.432558 -85.217)
		(end 4.417314 -83.232244)
		(width 0.1397)
		(layer "F.Cu")
		(net "SELF_1B&2B_HB")
	)
	(via
		(at 58.093864 -80.033876)
		(size 0.7112)
		(drill 0.3556)
		(layers "F.Cu" "B.Cu")
		(net "SELF_1B&2B_HB")
	)
	(via
		(at 158.724092 -101.837744)
		(size 0.7112)
		(drill 0.3556)
		(layers "F.Cu" "B.Cu")
		(net "DETECTOR_C")
	)
	(via
		(at 158.139892 -84.260944)
		(size 0.7112)
		(drill 0.3556)
		(layers "F.Cu" "B.Cu")
		(net "EMITTER_K")
	)
	(segment
		(start 135.556244 -81.813908)
		(end 136.635744 -81.813908)
		(width 0.1397)
		(layer "F.Cu")
		(net "TRAY_PRESENT_OUT_NET_B")
	)
	(segment
		(start 135.359394 -80.226408)
		(end 135.359394 -81.617058)
		(width 0.1397)
		(layer "F.Cu")
		(net "TRAY_PRESENT_OUT_NET_B")
	)
	(segment
		(start 135.359394 -81.617058)
		(end 135.556244 -81.813908)
		(width 0.1397)
		(layer "F.Cu")
		(net "TRAY_PRESENT_OUT_NET_B")
	)
	(via
		(at 136.635744 -81.813908)
		(size 0.7112)
		(drill 0.3556)
		(layers "F.Cu" "B.Cu")
		(net "TRAY_PRESENT_OUT_NET_B")
	)
	(segment
		(start 144.960086 -46.199806)
		(end 146.040094 -46.199806)
		(width 0.508)
		(layer "F.Cu")
		(net "P12V")
	)
	(segment
		(start 148.960078 -43.659806)
		(end 150.040086 -43.659806)
		(width 0.508)
		(layer "F.Cu")
		(net "P12V")
	)
	(segment
		(start 151.500078 -48.739806)
		(end 152.580086 -48.739806)
		(width 0.508)
		(layer "F.Cu")
		(net "P12V")
	)
	(segment
		(start 150.040086 -46.199806)
		(end 150.040086 -47.279814)
		(width 0.508)
		(layer "F.Cu")
		(net "P12V")
	)
	(segment
		(start 152.580086 -43.659806)
		(end 152.580086 -44.739814)
		(width 0.508)
		(layer "F.Cu")
		(net "P12V")
	)
	(segment
		(start 143.880078 -48.739806)
		(end 144.960086 -48.739806)
		(width 0.508)
		(layer "F.Cu")
		(net "P12V")
	)
	(segment
		(start 147.500086 -45.119798)
		(end 147.500086 -46.199806)
		(width 0.508)
		(layer "F.Cu")
		(net "P12V")
	)
	(segment
		(start 144.960086 -45.119798)
		(end 144.960086 -46.199806)
		(width 0.508)
		(layer "F.Cu")
		(net "P12V")
	)
	(segment
		(start 152.580086 -46.199806)
		(end 152.580086 -47.279814)
		(width 0.508)
		(layer "F.Cu")
		(net "P12V")
	)
	(segment
		(start 144.960086 -43.659806)
		(end 144.960086 -44.739814)
		(width 0.508)
		(layer "F.Cu")
		(net "P12V")
	)
	(segment
		(start 143.880078 -46.199806)
		(end 144.960086 -46.199806)
		(width 0.508)
		(layer "F.Cu")
		(net "P12V")
	)
	(segment
		(start 148.960078 -41.119806)
		(end 150.040086 -41.119806)
		(width 0.508)
		(layer "F.Cu")
		(net "P12V")
	)
	(segment
		(start 147.500086 -41.119806)
		(end 148.580094 -41.119806)
		(width 0.508)
		(layer "F.Cu")
		(net "P12V")
	)
	(segment
		(start 150.040086 -47.659798)
		(end 150.040086 -48.739806)
		(width 0.508)
		(layer "F.Cu")
		(net "P12V")
	)
	(segment
		(start 152.580086 -42.579798)
		(end 152.580086 -43.659806)
		(width 0.508)
		(layer "F.Cu")
		(net "P12V")
	)
	(segment
		(start 152.580086 -47.659798)
		(end 152.580086 -48.739806)
		(width 0.508)
		(layer "F.Cu")
		(net "P12V")
	)
	(segment
		(start 144.960086 -48.739806)
		(end 146.040094 -48.739806)
		(width 0.508)
		(layer "F.Cu")
		(net "P12V")
	)
	(segment
		(start 146.420078 -48.739806)
		(end 147.500086 -48.739806)
		(width 0.508)
		(layer "F.Cu")
		(net "P12V")
	)
	(segment
		(start 147.500086 -40.039798)
		(end 147.500086 -41.119806)
		(width 0.508)
		(layer "F.Cu")
		(net "P12V")
	)
	(segment
		(start 152.580086 -43.659806)
		(end 153.660094 -43.659806)
		(width 0.508)
		(layer "F.Cu")
		(net "P12V")
	)
	(segment
		(start 144.960086 -40.039798)
		(end 144.960086 -41.119806)
		(width 0.508)
		(layer "F.Cu")
		(net "P12V")
	)
	(segment
		(start 150.040086 -42.579798)
		(end 150.040086 -43.659806)
		(width 0.508)
		(layer "F.Cu")
		(net "P12V")
	)
	(segment
		(start 147.500086 -43.659806)
		(end 147.500086 -44.739814)
		(width 0.508)
		(layer "F.Cu")
		(net "P12V")
	)
	(segment
		(start 150.040086 -48.739806)
		(end 150.040086 -49.819814)
		(width 0.508)
		(layer "F.Cu")
		(net "P12V")
	)
	(segment
		(start 150.040086 -41.119806)
		(end 150.040086 -42.199814)
		(width 0.508)
		(layer "F.Cu")
		(net "P12V")
	)
	(segment
		(start 150.040086 -46.199806)
		(end 151.120094 -46.199806)
		(width 0.508)
		(layer "F.Cu")
		(net "P12V")
	)
	(segment
		(start 147.500086 -43.659806)
		(end 148.580094 -43.659806)
		(width 0.508)
		(layer "F.Cu")
		(net "P12V")
	)
	(segment
		(start 150.040086 -40.039798)
		(end 150.040086 -41.119806)
		(width 0.508)
		(layer "F.Cu")
		(net "P12V")
	)
	(segment
		(start 147.500086 -47.659798)
		(end 147.500086 -48.739806)
		(width 0.508)
		(layer "F.Cu")
		(net "P12V")
	)
	(segment
		(start 143.880078 -41.119806)
		(end 144.960086 -41.119806)
		(width 0.508)
		(layer "F.Cu")
		(net "P12V")
	)
	(segment
		(start 150.040086 -48.739806)
		(end 151.120094 -48.739806)
		(width 0.508)
		(layer "F.Cu")
		(net "P12V")
	)
	(segment
		(start 152.580086 -41.119806)
		(end 153.660094 -41.119806)
		(width 0.508)
		(layer "F.Cu")
		(net "P12V")
	)
	(segment
		(start 144.960086 -41.119806)
		(end 146.040094 -41.119806)
		(width 0.508)
		(layer "F.Cu")
		(net "P12V")
	)
	(segment
		(start 147.500086 -42.579798)
		(end 147.500086 -43.659806)
		(width 0.508)
		(layer "F.Cu")
		(net "P12V")
	)
	(segment
		(start 144.960086 -48.739806)
		(end 144.960086 -49.819814)
		(width 0.508)
		(layer "F.Cu")
		(net "P12V")
	)
	(segment
		(start 151.500078 -43.659806)
		(end 152.580086 -43.659806)
		(width 0.508)
		(layer "F.Cu")
		(net "P12V")
	)
	(segment
		(start 146.420078 -43.659806)
		(end 147.500086 -43.659806)
		(width 0.508)
		(layer "F.Cu")
		(net "P12V")
	)
	(segment
		(start 143.880078 -43.659806)
		(end 144.960086 -43.659806)
		(width 0.508)
		(layer "F.Cu")
		(net "P12V")
	)
	(segment
		(start 147.500086 -48.739806)
		(end 147.500086 -49.819814)
		(width 0.508)
		(layer "F.Cu")
		(net "P12V")
	)
	(segment
		(start 147.500086 -48.739806)
		(end 148.580094 -48.739806)
		(width 0.508)
		(layer "F.Cu")
		(net "P12V")
	)
	(segment
		(start 144.960086 -42.579798)
		(end 144.960086 -43.659806)
		(width 0.508)
		(layer "F.Cu")
		(net "P12V")
	)
	(segment
		(start 144.960086 -43.659806)
		(end 146.040094 -43.659806)
		(width 0.508)
		(layer "F.Cu")
		(net "P12V")
	)
	(segment
		(start 152.580086 -41.119806)
		(end 152.580086 -42.199814)
		(width 0.508)
		(layer "F.Cu")
		(net "P12V")
	)
	(segment
		(start 152.580086 -45.119798)
		(end 152.580086 -46.199806)
		(width 0.508)
		(layer "F.Cu")
		(net "P12V")
	)
	(segment
		(start 147.500086 -46.199806)
		(end 147.500086 -47.279814)
		(width 0.508)
		(layer "F.Cu")
		(net "P12V")
	)
	(segment
		(start 147.500086 -41.119806)
		(end 147.500086 -42.199814)
		(width 0.508)
		(layer "F.Cu")
		(net "P12V")
	)
	(segment
		(start 146.420078 -46.199806)
		(end 147.500086 -46.199806)
		(width 0.508)
		(layer "F.Cu")
		(net "P12V")
	)
	(segment
		(start 152.580086 -48.739806)
		(end 153.660094 -48.739806)
		(width 0.508)
		(layer "F.Cu")
		(net "P12V")
	)
	(segment
		(start 148.960078 -46.199806)
		(end 150.040086 -46.199806)
		(width 0.508)
		(layer "F.Cu")
		(net "P12V")
	)
	(segment
		(start 150.040086 -43.659806)
		(end 150.040086 -44.739814)
		(width 0.508)
		(layer "F.Cu")
		(net "P12V")
	)
	(segment
		(start 144.960086 -41.119806)
		(end 144.960086 -42.199814)
		(width 0.508)
		(layer "F.Cu")
		(net "P12V")
	)
	(segment
		(start 146.420078 -41.119806)
		(end 147.500086 -41.119806)
		(width 0.508)
		(layer "F.Cu")
		(net "P12V")
	)
	(segment
		(start 148.960078 -48.739806)
		(end 150.040086 -48.739806)
		(width 0.508)
		(layer "F.Cu")
		(net "P12V")
	)
	(segment
		(start 152.580086 -46.199806)
		(end 153.660094 -46.199806)
		(width 0.508)
		(layer "F.Cu")
		(net "P12V")
	)
	(segment
		(start 144.960086 -47.659798)
		(end 144.960086 -48.739806)
		(width 0.508)
		(layer "F.Cu")
		(net "P12V")
	)
	(segment
		(start 150.040086 -41.119806)
		(end 151.120094 -41.119806)
		(width 0.508)
		(layer "F.Cu")
		(net "P12V")
	)
	(segment
		(start 152.580086 -40.039798)
		(end 152.580086 -41.119806)
		(width 0.508)
		(layer "F.Cu")
		(net "P12V")
	)
	(segment
		(start 151.500078 -41.119806)
		(end 152.580086 -41.119806)
		(width 0.508)
		(layer "F.Cu")
		(net "P12V")
	)
	(segment
		(start 144.960086 -46.199806)
		(end 144.960086 -47.279814)
		(width 0.508)
		(layer "F.Cu")
		(net "P12V")
	)
	(segment
		(start 152.580086 -48.739806)
		(end 152.580086 -49.819814)
		(width 0.508)
		(layer "F.Cu")
		(net "P12V")
	)
	(segment
		(start 150.040086 -45.119798)
		(end 150.040086 -46.199806)
		(width 0.508)
		(layer "F.Cu")
		(net "P12V")
	)
	(segment
		(start 150.040086 -43.659806)
		(end 151.120094 -43.659806)
		(width 0.508)
		(layer "F.Cu")
		(net "P12V")
	)
	(segment
		(start 147.500086 -46.199806)
		(end 148.580094 -46.199806)
		(width 0.508)
		(layer "F.Cu")
		(net "P12V")
	)
	(segment
		(start 151.500078 -46.199806)
		(end 152.580086 -46.199806)
		(width 0.508)
		(layer "F.Cu")
		(net "P12V")
	)
	(via
		(at 39.730426 -42.286428)
		(size 0.7112)
		(drill 0.4064)
		(layers "F.Cu" "B.Cu")
		(net "P12V")
	)
	(via
		(at 123.302522 -40.81018)
		(size 0.7112)
		(drill 0.4064)
		(layers "F.Cu" "B.Cu")
		(net "P12V")
	)
	(via
		(at 1.630426 -29.586428)
		(size 0.7112)
		(drill 0.4064)
		(layers "F.Cu" "B.Cu")
		(net "P12V")
	)
	(via
		(at 54.970426 -21.966428)
		(size 0.7112)
		(drill 0.4064)
		(layers "F.Cu" "B.Cu")
		(net "P12V")
	)
	(via
		(at 19.410426 -32.126428)
		(size 0.7112)
		(drill 0.4064)
		(layers "F.Cu" "B.Cu")
		(net "P12V")
	)
	(via
		(at 44.810426 -32.126428)
		(size 0.7112)
		(drill 0.4064)
		(layers "F.Cu" "B.Cu")
		(net "P12V")
	)
	(via
		(at 6.710426 -44.826428)
		(size 0.7112)
		(drill 0.4064)
		(layers "F.Cu" "B.Cu")
		(net "P12V")
	)
	(via
		(at 34.650426 -16.886428)
		(size 0.7112)
		(drill 0.4064)
		(layers "F.Cu" "B.Cu")
		(net "P12V")
	)
	(via
		(at 136.163304 -42.042588)
		(size 0.7112)
		(drill 0.4064)
		(layers "F.Cu" "B.Cu")
		(net "P12V")
	)
	(via
		(at 129.748534 -41.938448)
		(size 0.7112)
		(drill 0.4064)
		(layers "F.Cu" "B.Cu")
		(net "P12V")
	)
	(via
		(at 18.542 -24.003)
		(size 0.7112)
		(drill 0.3556)
		(layers "F.Cu" "B.Cu")
		(net "P12V")
	)
	(via
		(at 24.490426 -37.206428)
		(size 0.7112)
		(drill 0.4064)
		(layers "F.Cu" "B.Cu")
		(net "P12V")
	)
	(via
		(at 4.170426 -39.746428)
		(size 0.7112)
		(drill 0.4064)
		(layers "F.Cu" "B.Cu")
		(net "P12V")
	)
	(via
		(at 131.170426 -32.126428)
		(size 0.7112)
		(drill 0.4064)
		(layers "F.Cu" "B.Cu")
		(net "P12V")
	)
	(via
		(at 34.650426 -42.286428)
		(size 0.7112)
		(drill 0.4064)
		(layers "F.Cu" "B.Cu")
		(net "P12V")
	)
	(via
		(at 100.690426 -16.886428)
		(size 0.7112)
		(drill 0.4064)
		(layers "F.Cu" "B.Cu")
		(net "P12V")
	)
	(via
		(at 136.250426 -27.046428)
		(size 0.7112)
		(drill 0.4064)
		(layers "F.Cu" "B.Cu")
		(net "P12V")
	)
	(via
		(at 6.710426 -47.366428)
		(size 0.7112)
		(drill 0.4064)
		(layers "F.Cu" "B.Cu")
		(net "P12V")
	)
	(via
		(at 1.630426 -32.126428)
		(size 0.7112)
		(drill 0.4064)
		(layers "F.Cu" "B.Cu")
		(net "P12V")
	)
	(via
		(at 44.810426 -37.206428)
		(size 0.7112)
		(drill 0.4064)
		(layers "F.Cu" "B.Cu")
		(net "P12V")
	)
	(via
		(at 95.610426 -21.966428)
		(size 0.7112)
		(drill 0.4064)
		(layers "F.Cu" "B.Cu")
		(net "P12V")
	)
	(via
		(at 100.690426 -21.966428)
		(size 0.7112)
		(drill 0.4064)
		(layers "F.Cu" "B.Cu")
		(net "P12V")
	)
	(via
		(at 39.730426 -21.966428)
		(size 0.7112)
		(drill 0.4064)
		(layers "F.Cu" "B.Cu")
		(net "P12V")
	)
	(via
		(at 60.050426 -32.126428)
		(size 0.7112)
		(drill 0.4064)
		(layers "F.Cu" "B.Cu")
		(net "P12V")
	)
	(via
		(at 139.375896 -43.414696)
		(size 0.7112)
		(drill 0.4064)
		(layers "F.Cu" "B.Cu")
		(net "P12V")
	)
	(via
		(at 128.681734 -41.938448)
		(size 0.7112)
		(drill 0.4064)
		(layers "F.Cu" "B.Cu")
		(net "P12V")
	)
	(via
		(at 75.290426 -47.366428)
		(size 0.7112)
		(drill 0.4064)
		(layers "F.Cu" "B.Cu")
		(net "P12V")
	)
	(via
		(at 121.230136 -43.278044)
		(size 0.7112)
		(drill 0.4064)
		(layers "F.Cu" "B.Cu")
		(net "P12V")
	)
	(via
		(at 107.116626 -43.251628)
		(size 0.7112)
		(drill 0.4064)
		(layers "F.Cu" "B.Cu")
		(net "P12V")
	)
	(via
		(at 9.250426 -21.966428)
		(size 0.7112)
		(drill 0.4064)
		(layers "F.Cu" "B.Cu")
		(net "P12V")
	)
	(via
		(at 120.163336 -44.344844)
		(size 0.7112)
		(drill 0.4064)
		(layers "F.Cu" "B.Cu")
		(net "P12V")
	)
	(via
		(at 49.890426 -27.046428)
		(size 0.7112)
		(drill 0.4064)
		(layers "F.Cu" "B.Cu")
		(net "P12V")
	)
	(via
		(at 6.710426 -39.746428)
		(size 0.7112)
		(drill 0.4064)
		(layers "F.Cu" "B.Cu")
		(net "P12V")
	)
	(via
		(at 131.170426 -16.886428)
		(size 0.7112)
		(drill 0.4064)
		(layers "F.Cu" "B.Cu")
		(net "P12V")
	)
	(via
		(at 128.681734 -40.871648)
		(size 0.7112)
		(drill 0.4064)
		(layers "F.Cu" "B.Cu")
		(net "P12V")
	)
	(via
		(at 95.610426 -32.126428)
		(size 0.7112)
		(drill 0.4064)
		(layers "F.Cu" "B.Cu")
		(net "P12V")
	)
	(via
		(at 141.330426 -27.046428)
		(size 0.7112)
		(drill 0.4064)
		(layers "F.Cu" "B.Cu")
		(net "P12V")
	)
	(via
		(at 135.096504 -40.975788)
		(size 0.7112)
		(drill 0.4064)
		(layers "F.Cu" "B.Cu")
		(net "P12V")
	)
	(via
		(at 11.912092 -29.955744)
		(size 0.7112)
		(drill 0.3556)
		(layers "F.Cu" "B.Cu")
		(net "P12V")
	)
	(via
		(at 85.450426 -32.126428)
		(size 0.7112)
		(drill 0.4064)
		(layers "F.Cu" "B.Cu")
		(net "P12V")
	)
	(via
		(at 116.1034 -43.3832)
		(size 0.7112)
		(drill 0.4064)
		(layers "F.Cu" "B.Cu")
		(net "P12V")
	)
	(via
		(at 146.410426 -27.046428)
		(size 0.7112)
		(drill 0.4064)
		(layers "F.Cu" "B.Cu")
		(net "P12V")
	)
	(via
		(at 60.050426 -47.366428)
		(size 0.7112)
		(drill 0.4064)
		(layers "F.Cu" "B.Cu")
		(net "P12V")
	)
	(via
		(at 105.770426 -21.966428)
		(size 0.7112)
		(drill 0.4064)
		(layers "F.Cu" "B.Cu")
		(net "P12V")
	)
	(via
		(at 9.250426 -47.366428)
		(size 0.7112)
		(drill 0.4064)
		(layers "F.Cu" "B.Cu")
		(net "P12V")
	)
	(via
		(at 106.049826 -44.318428)
		(size 0.7112)
		(drill 0.4064)
		(layers "F.Cu" "B.Cu")
		(net "P12V")
	)
	(via
		(at 4.170426 -29.586428)
		(size 0.7112)
		(drill 0.4064)
		(layers "F.Cu" "B.Cu")
		(net "P12V")
	)
	(via
		(at 126.59233 -44.36999)
		(size 0.7112)
		(drill 0.4064)
		(layers "F.Cu" "B.Cu")
		(net "P12V")
	)
	(via
		(at 118.237 -43.3832)
		(size 0.7112)
		(drill 0.4064)
		(layers "F.Cu" "B.Cu")
		(net "P12V")
	)
	(via
		(at 70.210426 -42.286428)
		(size 0.7112)
		(drill 0.4064)
		(layers "F.Cu" "B.Cu")
		(net "P12V")
	)
	(via
		(at 14.330426 -32.126428)
		(size 0.7112)
		(drill 0.4064)
		(layers "F.Cu" "B.Cu")
		(net "P12V")
	)
	(via
		(at 75.057 -42.926)
		(size 0.7112)
		(drill 0.4064)
		(layers "F.Cu" "B.Cu")
		(net "P12V")
	)
	(via
		(at 132.971794 -44.494196)
		(size 0.7112)
		(drill 0.4064)
		(layers "F.Cu" "B.Cu")
		(net "P12V")
	)
	(via
		(at -0.909574 -42.286428)
		(size 0.7112)
		(drill 0.4064)
		(layers "F.Cu" "B.Cu")
		(net "P12V")
	)
	(via
		(at 9.250426 -32.126428)
		(size 0.7112)
		(drill 0.4064)
		(layers "F.Cu" "B.Cu")
		(net "P12V")
	)
	(via
		(at 39.730426 -37.206428)
		(size 0.7112)
		(drill 0.4064)
		(layers "F.Cu" "B.Cu")
		(net "P12V")
	)
	(via
		(at 136.250426 -32.126428)
		(size 0.7112)
		(drill 0.4064)
		(layers "F.Cu" "B.Cu")
		(net "P12V")
	)
	(via
		(at 65.130426 -32.126428)
		(size 0.7112)
		(drill 0.4064)
		(layers "F.Cu" "B.Cu")
		(net "P12V")
	)
	(via
		(at 131.170426 -21.966428)
		(size 0.7112)
		(drill 0.4064)
		(layers "F.Cu" "B.Cu")
		(net "P12V")
	)
	(via
		(at 141.330426 -32.126428)
		(size 0.7112)
		(drill 0.4064)
		(layers "F.Cu" "B.Cu")
		(net "P12V")
	)
	(via
		(at 34.650426 -37.206428)
		(size 0.7112)
		(drill 0.4064)
		(layers "F.Cu" "B.Cu")
		(net "P12V")
	)
	(via
		(at 19.410426 -47.366428)
		(size 0.7112)
		(drill 0.4064)
		(layers "F.Cu" "B.Cu")
		(net "P12V")
	)
	(via
		(at 106.049826 -43.251628)
		(size 0.7112)
		(drill 0.4064)
		(layers "F.Cu" "B.Cu")
		(net "P12V")
	)
	(via
		(at 44.810426 -27.046428)
		(size 0.7112)
		(drill 0.4064)
		(layers "F.Cu" "B.Cu")
		(net "P12V")
	)
	(via
		(at 34.650426 -27.046428)
		(size 0.7112)
		(drill 0.4064)
		(layers "F.Cu" "B.Cu")
		(net "P12V")
	)
	(via
		(at 80.518 -42.291)
		(size 0.7112)
		(drill 0.4064)
		(layers "F.Cu" "B.Cu")
		(net "P12V")
	)
	(via
		(at 127.65913 -43.30319)
		(size 0.7112)
		(drill 0.4064)
		(layers "F.Cu" "B.Cu")
		(net "P12V")
	)
	(via
		(at 138.296904 -40.975788)
		(size 0.7112)
		(drill 0.4064)
		(layers "F.Cu" "B.Cu")
		(net "P12V")
	)
	(via
		(at -0.909574 -39.746428)
		(size 0.7112)
		(drill 0.4064)
		(layers "F.Cu" "B.Cu")
		(net "P12V")
	)
	(via
		(at 105.770426 -32.126428)
		(size 0.7112)
		(drill 0.4064)
		(layers "F.Cu" "B.Cu")
		(net "P12V")
	)
	(via
		(at 9.250426 -37.206428)
		(size 0.7112)
		(drill 0.4064)
		(layers "F.Cu" "B.Cu")
		(net "P12V")
	)
	(via
		(at 85.450426 -47.366428)
		(size 0.7112)
		(drill 0.4064)
		(layers "F.Cu" "B.Cu")
		(net "P12V")
	)
	(via
		(at 118.237 -44.45)
		(size 0.7112)
		(drill 0.4064)
		(layers "F.Cu" "B.Cu")
		(net "P12V")
	)
	(via
		(at 39.730426 -27.046428)
		(size 0.7112)
		(drill 0.4064)
		(layers "F.Cu" "B.Cu")
		(net "P12V")
	)
	(via
		(at 110.850426 -16.886428)
		(size 0.7112)
		(drill 0.4064)
		(layers "F.Cu" "B.Cu")
		(net "P12V")
	)
	(via
		(at 90.043 -42.291)
		(size 0.7112)
		(drill 0.4064)
		(layers "F.Cu" "B.Cu")
		(net "P12V")
	)
	(via
		(at 44.810426 -42.286428)
		(size 0.7112)
		(drill 0.4064)
		(layers "F.Cu" "B.Cu")
		(net "P12V")
	)
	(via
		(at 48.107092 -29.447744)
		(size 0.7112)
		(drill 0.3556)
		(layers "F.Cu" "B.Cu")
		(net "P12V")
	)
	(via
		(at 90.530426 -21.966428)
		(size 0.7112)
		(drill 0.4064)
		(layers "F.Cu" "B.Cu")
		(net "P12V")
	)
	(via
		(at 108.183426 -44.318428)
		(size 0.7112)
		(drill 0.4064)
		(layers "F.Cu" "B.Cu")
		(net "P12V")
	)
	(via
		(at 121.010426 -32.126428)
		(size 0.7112)
		(drill 0.4064)
		(layers "F.Cu" "B.Cu")
		(net "P12V")
	)
	(via
		(at 110.850426 -21.966428)
		(size 0.7112)
		(drill 0.4064)
		(layers "F.Cu" "B.Cu")
		(net "P12V")
	)
	(via
		(at 24.490426 -21.966428)
		(size 0.7112)
		(drill 0.4064)
		(layers "F.Cu" "B.Cu")
		(net "P12V")
	)
	(via
		(at 115.930426 -21.966428)
		(size 0.7112)
		(drill 0.4064)
		(layers "F.Cu" "B.Cu")
		(net "P12V")
	)
	(via
		(at 110.5662 -44.323)
		(size 0.7112)
		(drill 0.4064)
		(layers "F.Cu" "B.Cu")
		(net "P12V")
	)
	(via
		(at 85.450426 -16.886428)
		(size 0.7112)
		(drill 0.4064)
		(layers "F.Cu" "B.Cu")
		(net "P12V")
	)
	(via
		(at 90.805 -47.371)
		(size 0.7112)
		(drill 0.4064)
		(layers "F.Cu" "B.Cu")
		(net "P12V")
	)
	(via
		(at 116.1034 -44.45)
		(size 0.7112)
		(drill 0.4064)
		(layers "F.Cu" "B.Cu")
		(net "P12V")
	)
	(via
		(at 75.290426 -32.126428)
		(size 0.7112)
		(drill 0.4064)
		(layers "F.Cu" "B.Cu")
		(net "P12V")
	)
	(via
		(at 80.370426 -16.886428)
		(size 0.7112)
		(drill 0.4064)
		(layers "F.Cu" "B.Cu")
		(net "P12V")
	)
	(via
		(at 100.690426 -32.126428)
		(size 0.7112)
		(drill 0.4064)
		(layers "F.Cu" "B.Cu")
		(net "P12V")
	)
	(via
		(at 115.930426 -37.206428)
		(size 0.7112)
		(drill 0.4064)
		(layers "F.Cu" "B.Cu")
		(net "P12V")
	)
	(via
		(at 29.570426 -21.966428)
		(size 0.7112)
		(drill 0.4064)
		(layers "F.Cu" "B.Cu")
		(net "P12V")
	)
	(via
		(at 4.170426 -37.206428)
		(size 0.7112)
		(drill 0.4064)
		(layers "F.Cu" "B.Cu")
		(net "P12V")
	)
	(via
		(at 122.235722 -40.81018)
		(size 0.7112)
		(drill 0.4064)
		(layers "F.Cu" "B.Cu")
		(net "P12V")
	)
	(via
		(at 136.250426 -16.886428)
		(size 0.7112)
		(drill 0.4064)
		(layers "F.Cu" "B.Cu")
		(net "P12V")
	)
	(via
		(at 1.630426 -44.826428)
		(size 0.7112)
		(drill 0.4064)
		(layers "F.Cu" "B.Cu")
		(net "P12V")
	)
	(via
		(at 109.4994 -43.2562)
		(size 0.7112)
		(drill 0.4064)
		(layers "F.Cu" "B.Cu")
		(net "P12V")
	)
	(via
		(at 130.815334 -41.938448)
		(size 0.7112)
		(drill 0.4064)
		(layers "F.Cu" "B.Cu")
		(net "P12V")
	)
	(via
		(at 34.650426 -21.966428)
		(size 0.7112)
		(drill 0.4064)
		(layers "F.Cu" "B.Cu")
		(net "P12V")
	)
	(via
		(at 24.490426 -42.286428)
		(size 0.7112)
		(drill 0.4064)
		(layers "F.Cu" "B.Cu")
		(net "P12V")
	)
	(via
		(at 6.710426 -29.586428)
		(size 0.7112)
		(drill 0.4064)
		(layers "F.Cu" "B.Cu")
		(net "P12V")
	)
	(via
		(at 14.330426 -16.886428)
		(size 0.7112)
		(drill 0.4064)
		(layers "F.Cu" "B.Cu")
		(net "P12V")
	)
	(via
		(at 80.370426 -21.966428)
		(size 0.7112)
		(drill 0.4064)
		(layers "F.Cu" "B.Cu")
		(net "P12V")
	)
	(via
		(at 1.630426 -42.286428)
		(size 0.7112)
		(drill 0.4064)
		(layers "F.Cu" "B.Cu")
		(net "P12V")
	)
	(via
		(at 54.970426 -32.126428)
		(size 0.7112)
		(drill 0.4064)
		(layers "F.Cu" "B.Cu")
		(net "P12V")
	)
	(via
		(at 136.250426 -21.966428)
		(size 0.7112)
		(drill 0.4064)
		(layers "F.Cu" "B.Cu")
		(net "P12V")
	)
	(via
		(at 54.970426 -47.366428)
		(size 0.7112)
		(drill 0.4064)
		(layers "F.Cu" "B.Cu")
		(net "P12V")
	)
	(via
		(at 114.935 -43.2562)
		(size 0.7112)
		(drill 0.4064)
		(layers "F.Cu" "B.Cu")
		(net "P12V")
	)
	(via
		(at 69.723 -21.971)
		(size 0.7112)
		(drill 0.4064)
		(layers "F.Cu" "B.Cu")
		(net "P12V")
	)
	(via
		(at 11.912092 -38.845744)
		(size 0.7112)
		(drill 0.3556)
		(layers "F.Cu" "B.Cu")
		(net "P12V")
	)
	(via
		(at 88.366092 -29.828744)
		(size 0.7112)
		(drill 0.3556)
		(layers "F.Cu" "B.Cu")
		(net "P12V")
	)
	(via
		(at 110.850426 -27.046428)
		(size 0.7112)
		(drill 0.4064)
		(layers "F.Cu" "B.Cu")
		(net "P12V")
	)
	(via
		(at 122.235722 -41.87698)
		(size 0.7112)
		(drill 0.4064)
		(layers "F.Cu" "B.Cu")
		(net "P12V")
	)
	(via
		(at 54.970426 -42.286428)
		(size 0.7112)
		(drill 0.4064)
		(layers "F.Cu" "B.Cu")
		(net "P12V")
	)
	(via
		(at 129.748534 -40.871648)
		(size 0.7112)
		(drill 0.4064)
		(layers "F.Cu" "B.Cu")
		(net "P12V")
	)
	(via
		(at 121.010426 -37.206428)
		(size 0.7112)
		(drill 0.4064)
		(layers "F.Cu" "B.Cu")
		(net "P12V")
	)
	(via
		(at 19.410426 -27.046428)
		(size 0.7112)
		(drill 0.4064)
		(layers "F.Cu" "B.Cu")
		(net "P12V")
	)
	(via
		(at 114.935 -44.323)
		(size 0.7112)
		(drill 0.4064)
		(layers "F.Cu" "B.Cu")
		(net "P12V")
	)
	(via
		(at 14.330426 -21.966428)
		(size 0.7112)
		(drill 0.4064)
		(layers "F.Cu" "B.Cu")
		(net "P12V")
	)
	(via
		(at 4.170426 -21.966428)
		(size 0.7112)
		(drill 0.4064)
		(layers "F.Cu" "B.Cu")
		(net "P12V")
	)
	(via
		(at 6.710426 -42.286428)
		(size 0.7112)
		(drill 0.4064)
		(layers "F.Cu" "B.Cu")
		(net "P12V")
	)
	(via
		(at 100.690426 -42.286428)
		(size 0.7112)
		(drill 0.4064)
		(layers "F.Cu" "B.Cu")
		(net "P12V")
	)
	(via
		(at 34.650426 -47.366428)
		(size 0.7112)
		(drill 0.4064)
		(layers "F.Cu" "B.Cu")
		(net "P12V")
	)
	(via
		(at 110.5662 -43.2562)
		(size 0.7112)
		(drill 0.4064)
		(layers "F.Cu" "B.Cu")
		(net "P12V")
	)
	(via
		(at 76.708 -17.018)
		(size 0.7112)
		(drill 0.4064)
		(layers "F.Cu" "B.Cu")
		(net "P12V")
	)
	(via
		(at 4.170426 -34.666428)
		(size 0.7112)
		(drill 0.4064)
		(layers "F.Cu" "B.Cu")
		(net "P12V")
	)
	(via
		(at 85.450426 -27.046428)
		(size 0.7112)
		(drill 0.4064)
		(layers "F.Cu" "B.Cu")
		(net "P12V")
	)
	(via
		(at 49.890426 -47.366428)
		(size 0.7112)
		(drill 0.4064)
		(layers "F.Cu" "B.Cu")
		(net "P12V")
	)
	(via
		(at 4.170426 -44.826428)
		(size 0.7112)
		(drill 0.4064)
		(layers "F.Cu" "B.Cu")
		(net "P12V")
	)
	(via
		(at 95.610426 -27.046428)
		(size 0.7112)
		(drill 0.4064)
		(layers "F.Cu" "B.Cu")
		(net "P12V")
	)
	(via
		(at 105.770426 -27.046428)
		(size 0.7112)
		(drill 0.4064)
		(layers "F.Cu" "B.Cu")
		(net "P12V")
	)
	(via
		(at 121.230136 -44.344844)
		(size 0.7112)
		(drill 0.4064)
		(layers "F.Cu" "B.Cu")
		(net "P12V")
	)
	(via
		(at 126.090426 -21.966428)
		(size 0.7112)
		(drill 0.4064)
		(layers "F.Cu" "B.Cu")
		(net "P12V")
	)
	(via
		(at 110.850426 -32.126428)
		(size 0.7112)
		(drill 0.4064)
		(layers "F.Cu" "B.Cu")
		(net "P12V")
	)
	(via
		(at 124.369322 -41.87698)
		(size 0.7112)
		(drill 0.4064)
		(layers "F.Cu" "B.Cu")
		(net "P12V")
	)
	(via
		(at 124.369322 -40.81018)
		(size 0.7112)
		(drill 0.4064)
		(layers "F.Cu" "B.Cu")
		(net "P12V")
	)
	(via
		(at 29.570426 -47.366428)
		(size 0.7112)
		(drill 0.4064)
		(layers "F.Cu" "B.Cu")
		(net "P12V")
	)
	(via
		(at 131.882134 -40.871648)
		(size 0.7112)
		(drill 0.4064)
		(layers "F.Cu" "B.Cu")
		(net "P12V")
	)
	(via
		(at 39.730426 -47.366428)
		(size 0.7112)
		(drill 0.4064)
		(layers "F.Cu" "B.Cu")
		(net "P12V")
	)
	(via
		(at 135.096504 -42.042588)
		(size 0.7112)
		(drill 0.4064)
		(layers "F.Cu" "B.Cu")
		(net "P12V")
	)
	(via
		(at 138.296904 -42.042588)
		(size 0.7112)
		(drill 0.4064)
		(layers "F.Cu" "B.Cu")
		(net "P12V")
	)
	(via
		(at 131.170426 -27.046428)
		(size 0.7112)
		(drill 0.4064)
		(layers "F.Cu" "B.Cu")
		(net "P12V")
	)
	(via
		(at 44.810426 -47.366428)
		(size 0.7112)
		(drill 0.4064)
		(layers "F.Cu" "B.Cu")
		(net "P12V")
	)
	(via
		(at 14.330426 -37.206428)
		(size 0.7112)
		(drill 0.4064)
		(layers "F.Cu" "B.Cu")
		(net "P12V")
	)
	(via
		(at 134.038594 -44.494196)
		(size 0.7112)
		(drill 0.4064)
		(layers "F.Cu" "B.Cu")
		(net "P12V")
	)
	(via
		(at 111.633 -44.323)
		(size 0.7112)
		(drill 0.4064)
		(layers "F.Cu" "B.Cu")
		(net "P12V")
	)
	(via
		(at 29.570426 -37.206428)
		(size 0.7112)
		(drill 0.4064)
		(layers "F.Cu" "B.Cu")
		(net "P12V")
	)
	(via
		(at 126.090426 -32.126428)
		(size 0.7112)
		(drill 0.4064)
		(layers "F.Cu" "B.Cu")
		(net "P12V")
	)
	(via
		(at 111.633 -43.2562)
		(size 0.7112)
		(drill 0.4064)
		(layers "F.Cu" "B.Cu")
		(net "P12V")
	)
	(via
		(at 4.170426 -32.126428)
		(size 0.7112)
		(drill 0.4064)
		(layers "F.Cu" "B.Cu")
		(net "P12V")
	)
	(via
		(at 100.690426 -37.206428)
		(size 0.7112)
		(drill 0.4064)
		(layers "F.Cu" "B.Cu")
		(net "P12V")
	)
	(via
		(at 112.8014 -43.2562)
		(size 0.7112)
		(drill 0.4064)
		(layers "F.Cu" "B.Cu")
		(net "P12V")
	)
	(via
		(at 4.170426 -42.286428)
		(size 0.7112)
		(drill 0.4064)
		(layers "F.Cu" "B.Cu")
		(net "P12V")
	)
	(via
		(at 117.1702 -44.45)
		(size 0.7112)
		(drill 0.4064)
		(layers "F.Cu" "B.Cu")
		(net "P12V")
	)
	(via
		(at 54.970426 -27.046428)
		(size 0.7112)
		(drill 0.4064)
		(layers "F.Cu" "B.Cu")
		(net "P12V")
	)
	(via
		(at 133.705092 -29.701744)
		(size 0.7112)
		(drill 0.3556)
		(layers "F.Cu" "B.Cu")
		(net "P12V")
	)
	(via
		(at 19.410426 -42.286428)
		(size 0.7112)
		(drill 0.4064)
		(layers "F.Cu" "B.Cu")
		(net "P12V")
	)
	(via
		(at 107.116626 -44.318428)
		(size 0.7112)
		(drill 0.4064)
		(layers "F.Cu" "B.Cu")
		(net "P12V")
	)
	(via
		(at 85.450426 -37.206428)
		(size 0.7112)
		(drill 0.4064)
		(layers "F.Cu" "B.Cu")
		(net "P12V")
	)
	(via
		(at 4.170426 -27.046428)
		(size 0.7112)
		(drill 0.4064)
		(layers "F.Cu" "B.Cu")
		(net "P12V")
	)
	(via
		(at 90.530426 -32.126428)
		(size 0.7112)
		(drill 0.4064)
		(layers "F.Cu" "B.Cu")
		(net "P12V")
	)
	(via
		(at 69.469 -16.891)
		(size 0.7112)
		(drill 0.4064)
		(layers "F.Cu" "B.Cu")
		(net "P12V")
	)
	(via
		(at 125.436122 -41.87698)
		(size 0.7112)
		(drill 0.4064)
		(layers "F.Cu" "B.Cu")
		(net "P12V")
	)
	(via
		(at 139.375896 -44.481496)
		(size 0.7112)
		(drill 0.4064)
		(layers "F.Cu" "B.Cu")
		(net "P12V")
	)
	(via
		(at 1.630426 -34.666428)
		(size 0.7112)
		(drill 0.4064)
		(layers "F.Cu" "B.Cu")
		(net "P12V")
	)
	(via
		(at 121.010426 -21.966428)
		(size 0.7112)
		(drill 0.4064)
		(layers "F.Cu" "B.Cu")
		(net "P12V")
	)
	(via
		(at 24.490426 -47.366428)
		(size 0.7112)
		(drill 0.4064)
		(layers "F.Cu" "B.Cu")
		(net "P12V")
	)
	(via
		(at 113.8682 -44.323)
		(size 0.7112)
		(drill 0.4064)
		(layers "F.Cu" "B.Cu")
		(net "P12V")
	)
	(via
		(at 6.710426 -37.206428)
		(size 0.7112)
		(drill 0.4064)
		(layers "F.Cu" "B.Cu")
		(net "P12V")
	)
	(via
		(at 95.610426 -16.886428)
		(size 0.7112)
		(drill 0.4064)
		(layers "F.Cu" "B.Cu")
		(net "P12V")
	)
	(via
		(at 117.1702 -43.3832)
		(size 0.7112)
		(drill 0.4064)
		(layers "F.Cu" "B.Cu")
		(net "P12V")
	)
	(via
		(at 14.330426 -27.046428)
		(size 0.7112)
		(drill 0.4064)
		(layers "F.Cu" "B.Cu")
		(net "P12V")
	)
	(via
		(at 115.930426 -16.886428)
		(size 0.7112)
		(drill 0.4064)
		(layers "F.Cu" "B.Cu")
		(net "P12V")
	)
	(via
		(at 14.330426 -47.366428)
		(size 0.7112)
		(drill 0.4064)
		(layers "F.Cu" "B.Cu")
		(net "P12V")
	)
	(via
		(at 29.570426 -32.126428)
		(size 0.7112)
		(drill 0.4064)
		(layers "F.Cu" "B.Cu")
		(net "P12V")
	)
	(via
		(at 19.410426 -16.886428)
		(size 0.7112)
		(drill 0.4064)
		(layers "F.Cu" "B.Cu")
		(net "P12V")
	)
	(via
		(at 105.791 -42.164)
		(size 0.7112)
		(drill 0.4064)
		(layers "F.Cu" "B.Cu")
		(net "P12V")
	)
	(via
		(at 125.436122 -40.81018)
		(size 0.7112)
		(drill 0.4064)
		(layers "F.Cu" "B.Cu")
		(net "P12V")
	)
	(via
		(at -0.909574 -44.826428)
		(size 0.7112)
		(drill 0.4064)
		(layers "F.Cu" "B.Cu")
		(net "P12V")
	)
	(via
		(at 9.250426 -42.286428)
		(size 0.7112)
		(drill 0.4064)
		(layers "F.Cu" "B.Cu")
		(net "P12V")
	)
	(via
		(at 1.630426 -37.206428)
		(size 0.7112)
		(drill 0.4064)
		(layers "F.Cu" "B.Cu")
		(net "P12V")
	)
	(via
		(at 85.450426 -21.966428)
		(size 0.7112)
		(drill 0.4064)
		(layers "F.Cu" "B.Cu")
		(net "P12V")
	)
	(via
		(at 115.930426 -32.126428)
		(size 0.7112)
		(drill 0.4064)
		(layers "F.Cu" "B.Cu")
		(net "P12V")
	)
	(via
		(at 140.442696 -44.481496)
		(size 0.7112)
		(drill 0.4064)
		(layers "F.Cu" "B.Cu")
		(net "P12V")
	)
	(via
		(at 141.330426 -37.206428)
		(size 0.7112)
		(drill 0.4064)
		(layers "F.Cu" "B.Cu")
		(net "P12V")
	)
	(via
		(at 49.890426 -16.886428)
		(size 0.7112)
		(drill 0.4064)
		(layers "F.Cu" "B.Cu")
		(net "P12V")
	)
	(via
		(at 110.850426 -37.206428)
		(size 0.7112)
		(drill 0.4064)
		(layers "F.Cu" "B.Cu")
		(net "P12V")
	)
	(via
		(at 65.130426 -37.206428)
		(size 0.7112)
		(drill 0.4064)
		(layers "F.Cu" "B.Cu")
		(net "P12V")
	)
	(via
		(at 49.890426 -42.286428)
		(size 0.7112)
		(drill 0.4064)
		(layers "F.Cu" "B.Cu")
		(net "P12V")
	)
	(via
		(at 90.530426 -37.206428)
		(size 0.7112)
		(drill 0.4064)
		(layers "F.Cu" "B.Cu")
		(net "P12V")
	)
	(via
		(at 6.710426 -34.666428)
		(size 0.7112)
		(drill 0.4064)
		(layers "F.Cu" "B.Cu")
		(net "P12V")
	)
	(via
		(at 1.630426 -39.746428)
		(size 0.7112)
		(drill 0.4064)
		(layers "F.Cu" "B.Cu")
		(net "P12V")
	)
	(via
		(at 70.210426 -32.126428)
		(size 0.7112)
		(drill 0.4064)
		(layers "F.Cu" "B.Cu")
		(net "P12V")
	)
	(via
		(at 126.090426 -27.046428)
		(size 0.7112)
		(drill 0.4064)
		(layers "F.Cu" "B.Cu")
		(net "P12V")
	)
	(via
		(at 115.930426 -27.046428)
		(size 0.7112)
		(drill 0.4064)
		(layers "F.Cu" "B.Cu")
		(net "P12V")
	)
	(via
		(at 96.52 -42.291)
		(size 0.7112)
		(drill 0.4064)
		(layers "F.Cu" "B.Cu")
		(net "P12V")
	)
	(via
		(at -0.909574 -37.206428)
		(size 0.7112)
		(drill 0.4064)
		(layers "F.Cu" "B.Cu")
		(net "P12V")
	)
	(via
		(at 90.530426 -16.886428)
		(size 0.7112)
		(drill 0.4064)
		(layers "F.Cu" "B.Cu")
		(net "P12V")
	)
	(via
		(at 127.65913 -44.36999)
		(size 0.7112)
		(drill 0.4064)
		(layers "F.Cu" "B.Cu")
		(net "P12V")
	)
	(via
		(at 54.970426 -37.206428)
		(size 0.7112)
		(drill 0.4064)
		(layers "F.Cu" "B.Cu")
		(net "P12V")
	)
	(via
		(at 85.979 -42.164)
		(size 0.7112)
		(drill 0.4064)
		(layers "F.Cu" "B.Cu")
		(net "P12V")
	)
	(via
		(at 136.250426 -37.206428)
		(size 0.7112)
		(drill 0.4064)
		(layers "F.Cu" "B.Cu")
		(net "P12V")
	)
	(via
		(at 54.970426 -16.886428)
		(size 0.7112)
		(drill 0.4064)
		(layers "F.Cu" "B.Cu")
		(net "P12V")
	)
	(via
		(at 76.454 -21.971)
		(size 0.7112)
		(drill 0.4064)
		(layers "F.Cu" "B.Cu")
		(net "P12V")
	)
	(via
		(at 80.645 -47.371)
		(size 0.7112)
		(drill 0.4064)
		(layers "F.Cu" "B.Cu")
		(net "P12V")
	)
	(via
		(at 24.490426 -27.046428)
		(size 0.7112)
		(drill 0.4064)
		(layers "F.Cu" "B.Cu")
		(net "P12V")
	)
	(via
		(at 29.570426 -16.886428)
		(size 0.7112)
		(drill 0.4064)
		(layers "F.Cu" "B.Cu")
		(net "P12V")
	)
	(via
		(at 60.050426 -37.206428)
		(size 0.7112)
		(drill 0.4064)
		(layers "F.Cu" "B.Cu")
		(net "P12V")
	)
	(via
		(at -0.909574 -32.126428)
		(size 0.7112)
		(drill 0.4064)
		(layers "F.Cu" "B.Cu")
		(net "P12V")
	)
	(via
		(at 100.690426 -27.046428)
		(size 0.7112)
		(drill 0.4064)
		(layers "F.Cu" "B.Cu")
		(net "P12V")
	)
	(via
		(at 112.8014 -44.323)
		(size 0.7112)
		(drill 0.4064)
		(layers "F.Cu" "B.Cu")
		(net "P12V")
	)
	(via
		(at 131.882134 -41.938448)
		(size 0.7112)
		(drill 0.4064)
		(layers "F.Cu" "B.Cu")
		(net "P12V")
	)
	(via
		(at 19.410426 -21.966428)
		(size 0.7112)
		(drill 0.4064)
		(layers "F.Cu" "B.Cu")
		(net "P12V")
	)
	(via
		(at 141.330426 -21.966428)
		(size 0.7112)
		(drill 0.4064)
		(layers "F.Cu" "B.Cu")
		(net "P12V")
	)
	(via
		(at 136.163304 -40.975788)
		(size 0.7112)
		(drill 0.4064)
		(layers "F.Cu" "B.Cu")
		(net "P12V")
	)
	(via
		(at 90.530426 -27.046428)
		(size 0.7112)
		(drill 0.4064)
		(layers "F.Cu" "B.Cu")
		(net "P12V")
	)
	(via
		(at 140.442696 -43.414696)
		(size 0.7112)
		(drill 0.4064)
		(layers "F.Cu" "B.Cu")
		(net "P12V")
	)
	(via
		(at 34.650426 -32.126428)
		(size 0.7112)
		(drill 0.4064)
		(layers "F.Cu" "B.Cu")
		(net "P12V")
	)
	(via
		(at 60.050426 -42.286428)
		(size 0.7112)
		(drill 0.4064)
		(layers "F.Cu" "B.Cu")
		(net "P12V")
	)
	(via
		(at 126.59233 -43.30319)
		(size 0.7112)
		(drill 0.4064)
		(layers "F.Cu" "B.Cu")
		(net "P12V")
	)
	(via
		(at 49.890426 -32.126428)
		(size 0.7112)
		(drill 0.4064)
		(layers "F.Cu" "B.Cu")
		(net "P12V")
	)
	(via
		(at 69.977 -47.371)
		(size 0.7112)
		(drill 0.4064)
		(layers "F.Cu" "B.Cu")
		(net "P12V")
	)
	(via
		(at 105.770426 -16.886428)
		(size 0.7112)
		(drill 0.4064)
		(layers "F.Cu" "B.Cu")
		(net "P12V")
	)
	(via
		(at 95.610426 -47.366428)
		(size 0.7112)
		(drill 0.4064)
		(layers "F.Cu" "B.Cu")
		(net "P12V")
	)
	(via
		(at 6.710426 -32.126428)
		(size 0.7112)
		(drill 0.4064)
		(layers "F.Cu" "B.Cu")
		(net "P12V")
	)
	(via
		(at 39.730426 -16.886428)
		(size 0.7112)
		(drill 0.4064)
		(layers "F.Cu" "B.Cu")
		(net "P12V")
	)
	(via
		(at -0.909574 -34.666428)
		(size 0.7112)
		(drill 0.4064)
		(layers "F.Cu" "B.Cu")
		(net "P12V")
	)
	(via
		(at 80.370426 -27.046428)
		(size 0.7112)
		(drill 0.4064)
		(layers "F.Cu" "B.Cu")
		(net "P12V")
	)
	(via
		(at 131.170426 -37.206428)
		(size 0.7112)
		(drill 0.4064)
		(layers "F.Cu" "B.Cu")
		(net "P12V")
	)
	(via
		(at 49.890426 -21.966428)
		(size 0.7112)
		(drill 0.4064)
		(layers "F.Cu" "B.Cu")
		(net "P12V")
	)
	(via
		(at 113.8682 -43.2562)
		(size 0.7112)
		(drill 0.4064)
		(layers "F.Cu" "B.Cu")
		(net "P12V")
	)
	(via
		(at 123.302522 -41.87698)
		(size 0.7112)
		(drill 0.4064)
		(layers "F.Cu" "B.Cu")
		(net "P12V")
	)
	(via
		(at 80.370426 -32.126428)
		(size 0.7112)
		(drill 0.4064)
		(layers "F.Cu" "B.Cu")
		(net "P12V")
	)
	(via
		(at 126.090426 -37.206428)
		(size 0.7112)
		(drill 0.4064)
		(layers "F.Cu" "B.Cu")
		(net "P12V")
	)
	(via
		(at 146.410426 -32.126428)
		(size 0.7112)
		(drill 0.4064)
		(layers "F.Cu" "B.Cu")
		(net "P12V")
	)
	(via
		(at 4.170426 -47.366428)
		(size 0.7112)
		(drill 0.4064)
		(layers "F.Cu" "B.Cu")
		(net "P12V")
	)
	(via
		(at 11.912092 -46.465744)
		(size 0.7112)
		(drill 0.3556)
		(layers "F.Cu" "B.Cu")
		(net "P12V")
	)
	(via
		(at 100.690426 -47.366428)
		(size 0.7112)
		(drill 0.4064)
		(layers "F.Cu" "B.Cu")
		(net "P12V")
	)
	(via
		(at 19.410426 -37.206428)
		(size 0.7112)
		(drill 0.4064)
		(layers "F.Cu" "B.Cu")
		(net "P12V")
	)
	(via
		(at 65.130426 -21.966428)
		(size 0.7112)
		(drill 0.4064)
		(layers "F.Cu" "B.Cu")
		(net "P12V")
	)
	(via
		(at 44.810426 -21.966428)
		(size 0.7112)
		(drill 0.4064)
		(layers "F.Cu" "B.Cu")
		(net "P12V")
	)
	(via
		(at 49.890426 -37.206428)
		(size 0.7112)
		(drill 0.4064)
		(layers "F.Cu" "B.Cu")
		(net "P12V")
	)
	(via
		(at 24.490426 -32.126428)
		(size 0.7112)
		(drill 0.4064)
		(layers "F.Cu" "B.Cu")
		(net "P12V")
	)
	(via
		(at 14.330426 -42.286428)
		(size 0.7112)
		(drill 0.4064)
		(layers "F.Cu" "B.Cu")
		(net "P12V")
	)
	(via
		(at 65.130426 -16.886428)
		(size 0.7112)
		(drill 0.4064)
		(layers "F.Cu" "B.Cu")
		(net "P12V")
	)
	(via
		(at 63.881 -42.291)
		(size 0.7112)
		(drill 0.4064)
		(layers "F.Cu" "B.Cu")
		(net "P12V")
	)
	(via
		(at 76.2 -27.051)
		(size 0.7112)
		(drill 0.4064)
		(layers "F.Cu" "B.Cu")
		(net "P12V")
	)
	(via
		(at 132.971794 -43.427396)
		(size 0.7112)
		(drill 0.4064)
		(layers "F.Cu" "B.Cu")
		(net "P12V")
	)
	(via
		(at 65.130426 -27.046428)
		(size 0.7112)
		(drill 0.4064)
		(layers "F.Cu" "B.Cu")
		(net "P12V")
	)
	(via
		(at 95.610426 -37.206428)
		(size 0.7112)
		(drill 0.4064)
		(layers "F.Cu" "B.Cu")
		(net "P12V")
	)
	(via
		(at 105.770426 -37.206428)
		(size 0.7112)
		(drill 0.4064)
		(layers "F.Cu" "B.Cu")
		(net "P12V")
	)
	(via
		(at 60.050426 -21.966428)
		(size 0.7112)
		(drill 0.4064)
		(layers "F.Cu" "B.Cu")
		(net "P12V")
	)
	(via
		(at 121.010426 -16.886428)
		(size 0.7112)
		(drill 0.4064)
		(layers "F.Cu" "B.Cu")
		(net "P12V")
	)
	(via
		(at 110.871 -42.164)
		(size 0.7112)
		(drill 0.4064)
		(layers "F.Cu" "B.Cu")
		(net "P12V")
	)
	(via
		(at 24.490426 -16.886428)
		(size 0.7112)
		(drill 0.4064)
		(layers "F.Cu" "B.Cu")
		(net "P12V")
	)
	(via
		(at 65.130426 -47.366428)
		(size 0.7112)
		(drill 0.4064)
		(layers "F.Cu" "B.Cu")
		(net "P12V")
	)
	(via
		(at 137.230104 -42.042588)
		(size 0.7112)
		(drill 0.4064)
		(layers "F.Cu" "B.Cu")
		(net "P12V")
	)
	(via
		(at 9.250426 -27.046428)
		(size 0.7112)
		(drill 0.4064)
		(layers "F.Cu" "B.Cu")
		(net "P12V")
	)
	(via
		(at 137.230104 -40.975788)
		(size 0.7112)
		(drill 0.4064)
		(layers "F.Cu" "B.Cu")
		(net "P12V")
	)
	(via
		(at 108.183426 -43.251628)
		(size 0.7112)
		(drill 0.4064)
		(layers "F.Cu" "B.Cu")
		(net "P12V")
	)
	(via
		(at 121.010426 -27.046428)
		(size 0.7112)
		(drill 0.4064)
		(layers "F.Cu" "B.Cu")
		(net "P12V")
	)
	(via
		(at 44.810426 -16.886428)
		(size 0.7112)
		(drill 0.4064)
		(layers "F.Cu" "B.Cu")
		(net "P12V")
	)
	(via
		(at 69.723 -27.051)
		(size 0.7112)
		(drill 0.4064)
		(layers "F.Cu" "B.Cu")
		(net "P12V")
	)
	(via
		(at 109.4994 -44.323)
		(size 0.7112)
		(drill 0.4064)
		(layers "F.Cu" "B.Cu")
		(net "P12V")
	)
	(via
		(at 60.050426 -27.046428)
		(size 0.7112)
		(drill 0.4064)
		(layers "F.Cu" "B.Cu")
		(net "P12V")
	)
	(via
		(at 80.370426 -37.206428)
		(size 0.7112)
		(drill 0.4064)
		(layers "F.Cu" "B.Cu")
		(net "P12V")
	)
	(via
		(at 120.163336 -43.278044)
		(size 0.7112)
		(drill 0.4064)
		(layers "F.Cu" "B.Cu")
		(net "P12V")
	)
	(via
		(at 115.951 -42.291)
		(size 0.7112)
		(drill 0.4064)
		(layers "F.Cu" "B.Cu")
		(net "P12V")
	)
	(via
		(at 29.570426 -42.286428)
		(size 0.7112)
		(drill 0.4064)
		(layers "F.Cu" "B.Cu")
		(net "P12V")
	)
	(via
		(at 75.290426 -37.206428)
		(size 0.7112)
		(drill 0.4064)
		(layers "F.Cu" "B.Cu")
		(net "P12V")
	)
	(via
		(at 29.570426 -27.046428)
		(size 0.7112)
		(drill 0.4064)
		(layers "F.Cu" "B.Cu")
		(net "P12V")
	)
	(via
		(at 126.090426 -16.886428)
		(size 0.7112)
		(drill 0.4064)
		(layers "F.Cu" "B.Cu")
		(net "P12V")
	)
	(via
		(at -0.8509 -29.846016)
		(size 0.7112)
		(drill 0.4064)
		(layers "F.Cu" "B.Cu")
		(net "P12V")
	)
	(via
		(at 60.050426 -16.886428)
		(size 0.7112)
		(drill 0.4064)
		(layers "F.Cu" "B.Cu")
		(net "P12V")
	)
	(via
		(at 70.210426 -37.206428)
		(size 0.7112)
		(drill 0.4064)
		(layers "F.Cu" "B.Cu")
		(net "P12V")
	)
	(via
		(at 39.730426 -32.126428)
		(size 0.7112)
		(drill 0.4064)
		(layers "F.Cu" "B.Cu")
		(net "P12V")
	)
	(via
		(at 130.815334 -40.871648)
		(size 0.7112)
		(drill 0.4064)
		(layers "F.Cu" "B.Cu")
		(net "P12V")
	)
	(via
		(at 134.038594 -43.427396)
		(size 0.7112)
		(drill 0.4064)
		(layers "F.Cu" "B.Cu")
		(net "P12V")
	)
	(segment
		(start 147.500086 -41.119806)
		(end 147.500086 -42.199814)
		(width 0.508)
		(layer "B.Cu")
		(net "P12V")
	)
	(segment
		(start 144.960086 -48.739806)
		(end 144.960086 -49.819814)
		(width 0.508)
		(layer "B.Cu")
		(net "P12V")
	)
	(segment
		(start 143.880078 -46.199806)
		(end 144.960086 -46.199806)
		(width 0.508)
		(layer "B.Cu")
		(net "P12V")
	)
	(segment
		(start 144.960086 -41.119806)
		(end 144.960086 -42.199814)
		(width 0.508)
		(layer "B.Cu")
		(net "P12V")
	)
	(segment
		(start 152.580086 -41.119806)
		(end 153.660094 -41.119806)
		(width 0.508)
		(layer "B.Cu")
		(net "P12V")
	)
	(segment
		(start 151.500078 -41.119806)
		(end 152.580086 -41.119806)
		(width 0.508)
		(layer "B.Cu")
		(net "P12V")
	)
	(segment
		(start 148.960078 -48.739806)
		(end 150.040086 -48.739806)
		(width 0.508)
		(layer "B.Cu")
		(net "P12V")
	)
	(segment
		(start 146.420078 -48.739806)
		(end 147.500086 -48.739806)
		(width 0.508)
		(layer "B.Cu")
		(net "P12V")
	)
	(segment
		(start 152.580086 -46.199806)
		(end 153.660094 -46.199806)
		(width 0.508)
		(layer "B.Cu")
		(net "P12V")
	)
	(segment
		(start 151.500078 -46.199806)
		(end 152.580086 -46.199806)
		(width 0.508)
		(layer "B.Cu")
		(net "P12V")
	)
	(segment
		(start 152.580086 -43.659806)
		(end 152.580086 -44.739814)
		(width 0.508)
		(layer "B.Cu")
		(net "P12V")
	)
	(segment
		(start 150.040086 -48.739806)
		(end 151.120094 -48.739806)
		(width 0.508)
		(layer "B.Cu")
		(net "P12V")
	)
	(segment
		(start 144.960086 -41.119806)
		(end 146.040094 -41.119806)
		(width 0.508)
		(layer "B.Cu")
		(net "P12V")
	)
	(segment
		(start 147.500086 -43.659806)
		(end 148.580094 -43.659806)
		(width 0.508)
		(layer "B.Cu")
		(net "P12V")
	)
	(segment
		(start 150.040086 -47.659798)
		(end 150.040086 -48.739806)
		(width 0.508)
		(layer "B.Cu")
		(net "P12V")
	)
	(segment
		(start 147.500086 -45.119798)
		(end 147.500086 -46.199806)
		(width 0.508)
		(layer "B.Cu")
		(net "P12V")
	)
	(segment
		(start 150.040086 -41.119806)
		(end 151.120094 -41.119806)
		(width 0.508)
		(layer "B.Cu")
		(net "P12V")
	)
	(segment
		(start 150.040086 -45.119798)
		(end 150.040086 -46.199806)
		(width 0.508)
		(layer "B.Cu")
		(net "P12V")
	)
	(segment
		(start 150.040086 -42.579798)
		(end 150.040086 -43.659806)
		(width 0.508)
		(layer "B.Cu")
		(net "P12V")
	)
	(segment
		(start 150.040086 -40.039798)
		(end 150.040086 -41.119806)
		(width 0.508)
		(layer "B.Cu")
		(net "P12V")
	)
	(segment
		(start 147.500086 -48.739806)
		(end 147.500086 -49.819814)
		(width 0.508)
		(layer "B.Cu")
		(net "P12V")
	)
	(segment
		(start 152.580086 -48.739806)
		(end 153.660094 -48.739806)
		(width 0.508)
		(layer "B.Cu")
		(net "P12V")
	)
	(segment
		(start 144.960086 -40.039798)
		(end 144.960086 -41.119806)
		(width 0.508)
		(layer "B.Cu")
		(net "P12V")
	)
	(segment
		(start 150.040086 -41.119806)
		(end 150.040086 -42.199814)
		(width 0.508)
		(layer "B.Cu")
		(net "P12V")
	)
	(segment
		(start 144.960086 -47.659798)
		(end 144.960086 -48.739806)
		(width 0.508)
		(layer "B.Cu")
		(net "P12V")
	)
	(segment
		(start 148.960078 -43.659806)
		(end 150.040086 -43.659806)
		(width 0.508)
		(layer "B.Cu")
		(net "P12V")
	)
	(segment
		(start 147.500086 -46.199806)
		(end 148.580094 -46.199806)
		(width 0.508)
		(layer "B.Cu")
		(net "P12V")
	)
	(segment
		(start 152.580086 -41.119806)
		(end 152.580086 -42.199814)
		(width 0.508)
		(layer "B.Cu")
		(net "P12V")
	)
	(segment
		(start 144.960086 -46.199806)
		(end 146.040094 -46.199806)
		(width 0.508)
		(layer "B.Cu")
		(net "P12V")
	)
	(segment
		(start 152.580086 -46.199806)
		(end 152.580086 -47.279814)
		(width 0.508)
		(layer "B.Cu")
		(net "P12V")
	)
	(segment
		(start 152.580086 -48.739806)
		(end 152.580086 -49.819814)
		(width 0.508)
		(layer "B.Cu")
		(net "P12V")
	)
	(segment
		(start 144.960086 -45.119798)
		(end 144.960086 -46.199806)
		(width 0.508)
		(layer "B.Cu")
		(net "P12V")
	)
	(segment
		(start 147.500086 -40.039798)
		(end 147.500086 -41.119806)
		(width 0.508)
		(layer "B.Cu")
		(net "P12V")
	)
	(segment
		(start 152.580086 -42.579798)
		(end 152.580086 -43.659806)
		(width 0.508)
		(layer "B.Cu")
		(net "P12V")
	)
	(segment
		(start 146.420078 -43.659806)
		(end 147.500086 -43.659806)
		(width 0.508)
		(layer "B.Cu")
		(net "P12V")
	)
	(segment
		(start 151.500078 -48.739806)
		(end 152.580086 -48.739806)
		(width 0.508)
		(layer "B.Cu")
		(net "P12V")
	)
	(segment
		(start 152.580086 -45.119798)
		(end 152.580086 -46.199806)
		(width 0.508)
		(layer "B.Cu")
		(net "P12V")
	)
	(segment
		(start 147.500086 -41.119806)
		(end 148.580094 -41.119806)
		(width 0.508)
		(layer "B.Cu")
		(net "P12V")
	)
	(segment
		(start 150.040086 -46.199806)
		(end 150.040086 -47.279814)
		(width 0.508)
		(layer "B.Cu")
		(net "P12V")
	)
	(segment
		(start 147.500086 -46.199806)
		(end 147.500086 -47.279814)
		(width 0.508)
		(layer "B.Cu")
		(net "P12V")
	)
	(segment
		(start 150.040086 -43.659806)
		(end 151.120094 -43.659806)
		(width 0.508)
		(layer "B.Cu")
		(net "P12V")
	)
	(segment
		(start 144.960086 -43.659806)
		(end 144.960086 -44.739814)
		(width 0.508)
		(layer "B.Cu")
		(net "P12V")
	)
	(segment
		(start 143.880078 -48.739806)
		(end 144.960086 -48.739806)
		(width 0.508)
		(layer "B.Cu")
		(net "P12V")
	)
	(segment
		(start 147.500086 -42.579798)
		(end 147.500086 -43.659806)
		(width 0.508)
		(layer "B.Cu")
		(net "P12V")
	)
	(segment
		(start 152.580086 -47.659798)
		(end 152.580086 -48.739806)
		(width 0.508)
		(layer "B.Cu")
		(net "P12V")
	)
	(segment
		(start 143.880078 -43.659806)
		(end 144.960086 -43.659806)
		(width 0.508)
		(layer "B.Cu")
		(net "P12V")
	)
	(segment
		(start 144.960086 -48.739806)
		(end 146.040094 -48.739806)
		(width 0.508)
		(layer "B.Cu")
		(net "P12V")
	)
	(segment
		(start 151.500078 -43.659806)
		(end 152.580086 -43.659806)
		(width 0.508)
		(layer "B.Cu")
		(net "P12V")
	)
	(segment
		(start 152.580086 -40.039798)
		(end 152.580086 -41.119806)
		(width 0.508)
		(layer "B.Cu")
		(net "P12V")
	)
	(segment
		(start 146.420078 -41.119806)
		(end 147.500086 -41.119806)
		(width 0.508)
		(layer "B.Cu")
		(net "P12V")
	)
	(segment
		(start 147.500086 -43.659806)
		(end 147.500086 -44.739814)
		(width 0.508)
		(layer "B.Cu")
		(net "P12V")
	)
	(segment
		(start 144.960086 -46.199806)
		(end 144.960086 -47.279814)
		(width 0.508)
		(layer "B.Cu")
		(net "P12V")
	)
	(segment
		(start 152.580086 -43.659806)
		(end 153.660094 -43.659806)
		(width 0.508)
		(layer "B.Cu")
		(net "P12V")
	)
	(segment
		(start 146.420078 -46.199806)
		(end 147.500086 -46.199806)
		(width 0.508)
		(layer "B.Cu")
		(net "P12V")
	)
	(segment
		(start 144.960086 -42.579798)
		(end 144.960086 -43.659806)
		(width 0.508)
		(layer "B.Cu")
		(net "P12V")
	)
	(segment
		(start 147.500086 -47.659798)
		(end 147.500086 -48.739806)
		(width 0.508)
		(layer "B.Cu")
		(net "P12V")
	)
	(segment
		(start 148.960078 -41.119806)
		(end 150.040086 -41.119806)
		(width 0.508)
		(layer "B.Cu")
		(net "P12V")
	)
	(segment
		(start 150.040086 -43.659806)
		(end 150.040086 -44.739814)
		(width 0.508)
		(layer "B.Cu")
		(net "P12V")
	)
	(segment
		(start 150.040086 -48.739806)
		(end 150.040086 -49.819814)
		(width 0.508)
		(layer "B.Cu")
		(net "P12V")
	)
	(segment
		(start 150.040086 -46.199806)
		(end 151.120094 -46.199806)
		(width 0.508)
		(layer "B.Cu")
		(net "P12V")
	)
	(segment
		(start 144.960086 -43.659806)
		(end 146.040094 -43.659806)
		(width 0.508)
		(layer "B.Cu")
		(net "P12V")
	)
	(segment
		(start 148.960078 -46.199806)
		(end 150.040086 -46.199806)
		(width 0.508)
		(layer "B.Cu")
		(net "P12V")
	)
	(segment
		(start 147.500086 -48.739806)
		(end 148.580094 -48.739806)
		(width 0.508)
		(layer "B.Cu")
		(net "P12V")
	)
	(segment
		(start 143.880078 -41.119806)
		(end 144.960086 -41.119806)
		(width 0.508)
		(layer "B.Cu")
		(net "P12V")
	)
	(segment
		(start 133.6675 -83.531964)
		(end 133.321552 -83.877912)
		(width 0.1397)
		(layer "F.Cu")
		(net "TRAY PRESENT_OUT#_C")
	)
	(segment
		(start 133.6675 -82.804)
		(end 133.6675 -83.531964)
		(width 0.1397)
		(layer "F.Cu")
		(net "TRAY PRESENT_OUT#_C")
	)
	(segment
		(start 134.375144 -81.080356)
		(end 133.6675 -81.788)
		(width 0.1397)
		(layer "F.Cu")
		(net "TRAY PRESENT_OUT#_C")
	)
	(segment
		(start 134.375144 -78.321408)
		(end 134.375144 -81.080356)
		(width 0.1397)
		(layer "F.Cu")
		(net "TRAY PRESENT_OUT#_C")
	)
	(segment
		(start 133.6675 -81.788)
		(end 133.6675 -82.804)
		(width 0.1397)
		(layer "F.Cu")
		(net "TRAY PRESENT_OUT#_C")
	)
	(via
		(at 133.321552 -83.877912)
		(size 0.7112)
		(drill 0.3556)
		(layers "F.Cu" "B.Cu")
		(net "TRAY PRESENT_OUT#_C")
	)
	(segment
		(start 14.625828 -91.481402)
		(end 14.625828 -92.291408)
		(width 0.381)
		(layer "F.Cu")
		(net "GND")
	)
	(segment
		(start 135.556244 -82.906108)
		(end 136.432544 -82.906108)
		(width 0.508)
		(layer "F.Cu")
		(net "GND")
	)
	(segment
		(start 15.722092 -91.169744)
		(end 14.937486 -91.169744)
		(width 0.381)
		(layer "F.Cu")
		(net "GND")
	)
	(segment
		(start 14.937486 -91.169744)
		(end 14.625828 -91.481402)
		(width 0.381)
		(layer "F.Cu")
		(net "GND")
	)
	(segment
		(start -1.676908 -90.729308)
		(end -6.99897 -90.729308)
		(width 0.762)
		(layer "F.Cu")
		(net "GND")
	)
	(segment
		(start -6.99897 -83.109308)
		(end -1.803908 -83.109308)
		(width 0.762)
		(layer "F.Cu")
		(net "GND")
	)
	(segment
		(start 137.795 -65.524634)
		(end 138.8364 -65.524634)
		(width 0.508)
		(layer "F.Cu")
		(net "GND")
	)
	(segment
		(start 133.390894 -80.226408)
		(end 133.390894 -78.994)
		(width 0.762)
		(layer "F.Cu")
		(net "GND")
	)
	(via
		(at 1.879092 -70.341744)
		(size 0.7112)
		(drill 0.4064)
		(layers "F.Cu" "B.Cu")
		(net "GND")
	)
	(via
		(at 24.490426 -11.806428)
		(size 0.7112)
		(drill 0.4064)
		(layers "F.Cu" "B.Cu")
		(net "GND")
	)
	(via
		(at 33.528 -112.395)
		(size 0.7112)
		(drill 0.4064)
		(layers "F.Cu" "B.Cu")
		(net "GND")
	)
	(via
		(at 161.066226 -11.806428)
		(size 0.7112)
		(drill 0.4064)
		(layers "F.Cu" "B.Cu")
		(net "GND")
	)
	(via
		(at 121.158 -106.172)
		(size 0.7112)
		(drill 0.4064)
		(layers "F.Cu" "B.Cu")
		(net "GND")
	)
	(via
		(at 100.081588 -78.298548)
		(size 0.7112)
		(drill 0.3556)
		(layers "F.Cu" "B.Cu")
		(net "GND")
	)
	(via
		(at 131.170426 -11.806428)
		(size 0.7112)
		(drill 0.4064)
		(layers "F.Cu" "B.Cu")
		(net "GND")
	)
	(via
		(at 85.450426 -11.806428)
		(size 0.7112)
		(drill 0.4064)
		(layers "F.Cu" "B.Cu")
		(net "GND")
	)
	(via
		(at 153.014426 -11.806428)
		(size 0.7112)
		(drill 0.4064)
		(layers "F.Cu" "B.Cu")
		(net "GND")
	)
	(via
		(at 9.499092 -52.561744)
		(size 0.7112)
		(drill 0.4064)
		(layers "F.Cu" "B.Cu")
		(net "GND")
	)
	(via
		(at 54.970426 -1.646428)
		(size 0.7112)
		(drill 0.4064)
		(layers "F.Cu" "B.Cu")
		(net "GND")
	)
	(via
		(at 95.610426 -1.646428)
		(size 0.7112)
		(drill 0.4064)
		(layers "F.Cu" "B.Cu")
		(net "GND")
	)
	(via
		(at 106.2482 -50.165)
		(size 0.7112)
		(drill 0.4064)
		(layers "F.Cu" "B.Cu")
		(net "GND")
	)
	(via
		(at 60.050426 -1.646428)
		(size 0.7112)
		(drill 0.4064)
		(layers "F.Cu" "B.Cu")
		(net "GND")
	)
	(via
		(at 106.273092 -72.881744)
		(size 0.7112)
		(drill 0.4064)
		(layers "F.Cu" "B.Cu")
		(net "GND")
	)
	(via
		(at 80.09382 -90.922856)
		(size 0.7112)
		(drill 0.4064)
		(layers "F.Cu" "B.Cu")
		(net "GND")
	)
	(via
		(at 100.41382 -106.162856)
		(size 0.7112)
		(drill 0.4064)
		(layers "F.Cu" "B.Cu")
		(net "GND")
	)
	(via
		(at 95.859092 -57.641744)
		(size 0.7112)
		(drill 0.4064)
		(layers "F.Cu" "B.Cu")
		(net "GND")
	)
	(via
		(at 146.685 -77.47)
		(size 0.7112)
		(drill 0.4064)
		(layers "F.Cu" "B.Cu")
		(net "GND")
	)
	(via
		(at 100.939092 -62.721744)
		(size 0.7112)
		(drill 0.4064)
		(layers "F.Cu" "B.Cu")
		(net "GND")
	)
	(via
		(at 121.285 -94.107)
		(size 0.7112)
		(drill 0.3556)
		(layers "F.Cu" "B.Cu")
		(net "GND")
	)
	(via
		(at 34.899092 -67.801744)
		(size 0.7112)
		(drill 0.4064)
		(layers "F.Cu" "B.Cu")
		(net "GND")
	)
	(via
		(at 148.645626 -11.806428)
		(size 0.7112)
		(drill 0.4064)
		(layers "F.Cu" "B.Cu")
		(net "GND")
	)
	(via
		(at 136.432544 -82.906108)
		(size 0.7112)
		(drill 0.4064)
		(layers "F.Cu" "B.Cu")
		(net "GND")
	)
	(via
		(at 108.3818 -50.165)
		(size 0.7112)
		(drill 0.4064)
		(layers "F.Cu" "B.Cu")
		(net "GND")
	)
	(via
		(at 8.864092 -87.613744)
		(size 0.7112)
		(drill 0.4064)
		(layers "F.Cu" "B.Cu")
		(net "GND")
	)
	(via
		(at 90.779092 -57.641744)
		(size 0.7112)
		(drill 0.4064)
		(layers "F.Cu" "B.Cu")
		(net "GND")
	)
	(via
		(at 34.899092 -62.721744)
		(size 0.7112)
		(drill 0.4064)
		(layers "F.Cu" "B.Cu")
		(net "GND")
	)
	(via
		(at 65.130426 -6.726428)
		(size 0.7112)
		(drill 0.4064)
		(layers "F.Cu" "B.Cu")
		(net "GND")
	)
	(via
		(at 1.879092 -55.101744)
		(size 0.7112)
		(drill 0.4064)
		(layers "F.Cu" "B.Cu")
		(net "GND")
	)
	(via
		(at 116.179092 -62.721744)
		(size 0.7112)
		(drill 0.4064)
		(layers "F.Cu" "B.Cu")
		(net "GND")
	)
	(via
		(at 121.998994 -52.476908)
		(size 0.7112)
		(drill 0.4064)
		(layers "F.Cu" "B.Cu")
		(net "GND")
	)
	(via
		(at 24.485092 -85.835744)
		(size 0.7112)
		(drill 0.4064)
		(layers "F.Cu" "B.Cu")
		(net "GND")
	)
	(via
		(at 155.295092 -22.081744)
		(size 0.7112)
		(drill 0.4064)
		(layers "F.Cu" "B.Cu")
		(net "GND")
	)
	(via
		(at 160.756092 -102.853744)
		(size 0.7112)
		(drill 0.4064)
		(layers "F.Cu" "B.Cu")
		(net "GND")
	)
	(via
		(at 95.859092 -52.434744)
		(size 0.7112)
		(drill 0.4064)
		(layers "F.Cu" "B.Cu")
		(net "GND")
	)
	(via
		(at 29.057092 -78.469744)
		(size 0.7112)
		(drill 0.3556)
		(layers "F.Cu" "B.Cu")
		(net "GND")
	)
	(via
		(at 24.739092 -52.561744)
		(size 0.7112)
		(drill 0.4064)
		(layers "F.Cu" "B.Cu")
		(net "GND")
	)
	(via
		(at 118.4148 -51.2318)
		(size 0.7112)
		(drill 0.4064)
		(layers "F.Cu" "B.Cu")
		(net "GND")
	)
	(via
		(at 95.859092 -72.881744)
		(size 0.7112)
		(drill 0.4064)
		(layers "F.Cu" "B.Cu")
		(net "GND")
	)
	(via
		(at 132.308092 -58.022744)
		(size 0.7112)
		(drill 0.4064)
		(layers "F.Cu" "B.Cu")
		(net "GND")
	)
	(via
		(at 124.132594 -52.476908)
		(size 0.7112)
		(drill 0.4064)
		(layers "F.Cu" "B.Cu")
		(net "GND")
	)
	(via
		(at 105.49382 -90.922856)
		(size 0.7112)
		(drill 0.4064)
		(layers "F.Cu" "B.Cu")
		(net "GND")
	)
	(via
		(at 110.617 -51.2318)
		(size 0.7112)
		(drill 0.4064)
		(layers "F.Cu" "B.Cu")
		(net "GND")
	)
	(via
		(at 55.219092 -67.801744)
		(size 0.7112)
		(drill 0.4064)
		(layers "F.Cu" "B.Cu")
		(net "GND")
	)
	(via
		(at 115.443 -118.237)
		(size 0.7112)
		(drill 0.4064)
		(layers "F.Cu" "B.Cu")
		(net "GND")
	)
	(via
		(at 39.45382 -96.002856)
		(size 0.7112)
		(drill 0.4064)
		(layers "F.Cu" "B.Cu")
		(net "GND")
	)
	(via
		(at 29.29382 -106.162856)
		(size 0.7112)
		(drill 0.4064)
		(layers "F.Cu" "B.Cu")
		(net "GND")
	)
	(via
		(at 115.671092 -85.962744)
		(size 0.7112)
		(drill 0.4064)
		(layers "F.Cu" "B.Cu")
		(net "GND")
	)
	(via
		(at 15.849092 -85.962744)
		(size 0.7112)
		(drill 0.4064)
		(layers "F.Cu" "B.Cu")
		(net "GND")
	)
	(via
		(at 117.348 -51.2318)
		(size 0.7112)
		(drill 0.4064)
		(layers "F.Cu" "B.Cu")
		(net "GND")
	)
	(via
		(at 90.779092 -52.434744)
		(size 0.7112)
		(drill 0.4064)
		(layers "F.Cu" "B.Cu")
		(net "GND")
	)
	(via
		(at 75.539092 -67.801744)
		(size 0.7112)
		(drill 0.4064)
		(layers "F.Cu" "B.Cu")
		(net "GND")
	)
	(via
		(at 6.959092 -65.261744)
		(size 0.7112)
		(drill 0.4064)
		(layers "F.Cu" "B.Cu")
		(net "GND")
	)
	(via
		(at 59.77382 -85.842856)
		(size 0.7112)
		(drill 0.4064)
		(layers "F.Cu" "B.Cu")
		(net "GND")
	)
	(via
		(at 140.505434 -49.955958)
		(size 0.7112)
		(drill 0.4064)
		(layers "F.Cu" "B.Cu")
		(net "GND")
	)
	(via
		(at 44.53382 -90.922856)
		(size 0.7112)
		(drill 0.4064)
		(layers "F.Cu" "B.Cu")
		(net "GND")
	)
	(via
		(at 137.922 -50.165)
		(size 0.7112)
		(drill 0.3556)
		(layers "F.Cu" "B.Cu")
		(net "GND")
	)
	(via
		(at 54.69382 -85.842856)
		(size 0.7112)
		(drill 0.4064)
		(layers "F.Cu" "B.Cu")
		(net "GND")
	)
	(via
		(at 23.241 -118.237)
		(size 0.7112)
		(drill 0.4064)
		(layers "F.Cu" "B.Cu")
		(net "GND")
	)
	(via
		(at 105.770426 -11.806428)
		(size 0.7112)
		(drill 0.4064)
		(layers "F.Cu" "B.Cu")
		(net "GND")
	)
	(via
		(at 90.530426 -1.646428)
		(size 0.7112)
		(drill 0.4064)
		(layers "F.Cu" "B.Cu")
		(net "GND")
	)
	(via
		(at 120.113298 -50.030888)
		(size 0.7112)
		(drill 0.4064)
		(layers "F.Cu" "B.Cu")
		(net "GND")
	)
	(via
		(at 6.35 -87.122)
		(size 0.7112)
		(drill 0.4064)
		(layers "F.Cu" "B.Cu")
		(net "GND")
	)
	(via
		(at 105.49382 -96.002856)
		(size 0.7112)
		(drill 0.4064)
		(layers "F.Cu" "B.Cu")
		(net "GND")
	)
	(via
		(at -1.76276 -80.326738)
		(size 0.7112)
		(drill 0.4064)
		(layers "F.Cu" "B.Cu")
		(net "GND")
	)
	(via
		(at 139.908026 -11.806428)
		(size 0.7112)
		(drill 0.4064)
		(layers "F.Cu" "B.Cu")
		(net "GND")
	)
	(via
		(at 4.419092 -72.881744)
		(size 0.7112)
		(drill 0.4064)
		(layers "F.Cu" "B.Cu")
		(net "GND")
	)
	(via
		(at 110.591092 -91.042744)
		(size 0.7112)
		(drill 0.4064)
		(layers "F.Cu" "B.Cu")
		(net "GND")
	)
	(via
		(at 65.379092 -72.881744)
		(size 0.7112)
		(drill 0.4064)
		(layers "F.Cu" "B.Cu")
		(net "GND")
	)
	(via
		(at 95.33382 -85.842856)
		(size 0.7112)
		(drill 0.4064)
		(layers "F.Cu" "B.Cu")
		(net "GND")
	)
	(via
		(at 100.939092 -57.641744)
		(size 0.7112)
		(drill 0.4064)
		(layers "F.Cu" "B.Cu")
		(net "GND")
	)
	(via
		(at 135.539226 -1.646428)
		(size 0.7112)
		(drill 0.4064)
		(layers "F.Cu" "B.Cu")
		(net "GND")
	)
	(via
		(at 107.315 -50.165)
		(size 0.7112)
		(drill 0.4064)
		(layers "F.Cu" "B.Cu")
		(net "GND")
	)
	(via
		(at 95.33382 -96.002856)
		(size 0.7112)
		(drill 0.4064)
		(layers "F.Cu" "B.Cu")
		(net "GND")
	)
	(via
		(at 127.572008 -50.898806)
		(size 0.7112)
		(drill 0.4064)
		(layers "F.Cu" "B.Cu")
		(net "GND")
	)
	(via
		(at 44.810426 -11.806428)
		(size 0.7112)
		(drill 0.4064)
		(layers "F.Cu" "B.Cu")
		(net "GND")
	)
	(via
		(at 100.41382 -96.002856)
		(size 0.7112)
		(drill 0.4064)
		(layers "F.Cu" "B.Cu")
		(net "GND")
	)
	(via
		(at 160.02 -98.425)
		(size 0.7112)
		(drill 0.4064)
		(layers "F.Cu" "B.Cu")
		(net "GND")
	)
	(via
		(at 132.984494 -50.960528)
		(size 0.7112)
		(drill 0.4064)
		(layers "F.Cu" "B.Cu")
		(net "GND")
	)
	(via
		(at 118.4148 -50.165)
		(size 0.7112)
		(drill 0.4064)
		(layers "F.Cu" "B.Cu")
		(net "GND")
	)
	(via
		(at 128.55829 -53.481478)
		(size 0.7112)
		(drill 0.4064)
		(layers "F.Cu" "B.Cu")
		(net "GND")
	)
	(via
		(at 140.462 -107.95)
		(size 0.7112)
		(drill 0.4064)
		(layers "F.Cu" "B.Cu")
		(net "GND")
	)
	(via
		(at 121.010426 -11.806428)
		(size 0.7112)
		(drill 0.4064)
		(layers "F.Cu" "B.Cu")
		(net "GND")
	)
	(via
		(at 115.671092 -91.042744)
		(size 0.7112)
		(drill 0.4064)
		(layers "F.Cu" "B.Cu")
		(net "GND")
	)
	(via
		(at 145.700242 -17.009618)
		(size 0.7112)
		(drill 0.4064)
		(layers "F.Cu" "B.Cu")
		(net "GND")
	)
	(via
		(at 137.230358 -53.438806)
		(size 0.7112)
		(drill 0.4064)
		(layers "F.Cu" "B.Cu")
		(net "GND")
	)
	(via
		(at 59.90082 -112.385856)
		(size 0.7112)
		(drill 0.4064)
		(layers "F.Cu" "B.Cu")
		(net "GND")
	)
	(via
		(at 49.61382 -96.002856)
		(size 0.7112)
		(drill 0.4064)
		(layers "F.Cu" "B.Cu")
		(net "GND")
	)
	(via
		(at 156.464 -44.069)
		(size 0.7112)
		(drill 0.4064)
		(layers "F.Cu" "B.Cu")
		(net "GND")
	)
	(via
		(at 4.419092 -52.561744)
		(size 0.7112)
		(drill 0.4064)
		(layers "F.Cu" "B.Cu")
		(net "GND")
	)
	(via
		(at 100.939092 -67.801744)
		(size 0.7112)
		(drill 0.4064)
		(layers "F.Cu" "B.Cu")
		(net "GND")
	)
	(via
		(at 139.573 -77.597)
		(size 0.7112)
		(drill 0.4064)
		(layers "F.Cu" "B.Cu")
		(net "GND")
	)
	(via
		(at 85.30082 -112.385856)
		(size 0.7112)
		(drill 0.4064)
		(layers "F.Cu" "B.Cu")
		(net "GND")
	)
	(via
		(at 55.854092 -118.220744)
		(size 0.7112)
		(drill 0.4064)
		(layers "F.Cu" "B.Cu")
		(net "GND")
	)
	(via
		(at 70.210426 -11.806428)
		(size 0.7112)
		(drill 0.4064)
		(layers "F.Cu" "B.Cu")
		(net "GND")
	)
	(via
		(at 110.850426 -11.806428)
		(size 0.7112)
		(drill 0.4064)
		(layers "F.Cu" "B.Cu")
		(net "GND")
	)
	(via
		(at 123.065794 -53.543708)
		(size 0.7112)
		(drill 0.4064)
		(layers "F.Cu" "B.Cu")
		(net "GND")
	)
	(via
		(at 39.730426 -6.726428)
		(size 0.7112)
		(drill 0.4064)
		(layers "F.Cu" "B.Cu")
		(net "GND")
	)
	(via
		(at 155.258262 -16.688054)
		(size 0.7112)
		(drill 0.4064)
		(layers "F.Cu" "B.Cu")
		(net "GND")
	)
	(via
		(at 112.9792 -51.2318)
		(size 0.7112)
		(drill 0.4064)
		(layers "F.Cu" "B.Cu")
		(net "GND")
	)
	(via
		(at 15.722092 -91.169744)
		(size 0.7112)
		(drill 0.4064)
		(layers "F.Cu" "B.Cu")
		(net "GND")
	)
	(via
		(at 115.1128 -50.165)
		(size 0.7112)
		(drill 0.4064)
		(layers "F.Cu" "B.Cu")
		(net "GND")
	)
	(via
		(at 144.447514 -16.868902)
		(size 0.7112)
		(drill 0.3556)
		(layers "F.Cu" "B.Cu")
		(net "GND")
	)
	(via
		(at 111.734092 -118.220744)
		(size 0.7112)
		(drill 0.4064)
		(layers "F.Cu" "B.Cu")
		(net "GND")
	)
	(via
		(at 110.70082 -112.385856)
		(size 0.7112)
		(drill 0.4064)
		(layers "F.Cu" "B.Cu")
		(net "GND")
	)
	(via
		(at 80.619092 -52.434744)
		(size 0.7112)
		(drill 0.4064)
		(layers "F.Cu" "B.Cu")
		(net "GND")
	)
	(via
		(at 105.62082 -112.385856)
		(size 0.7112)
		(drill 0.4064)
		(layers "F.Cu" "B.Cu")
		(net "GND")
	)
	(via
		(at 90.25382 -106.162856)
		(size 0.7112)
		(drill 0.4064)
		(layers "F.Cu" "B.Cu")
		(net "GND")
	)
	(via
		(at 157.383226 -1.646428)
		(size 0.7112)
		(drill 0.4064)
		(layers "F.Cu" "B.Cu")
		(net "GND")
	)
	(via
		(at 126.746 -106.299)
		(size 0.7112)
		(drill 0.4064)
		(layers "F.Cu" "B.Cu")
		(net "GND")
	)
	(via
		(at 92.557092 -109.457744)
		(size 0.7112)
		(drill 0.3556)
		(layers "F.Cu" "B.Cu")
		(net "GND")
	)
	(via
		(at 75.290426 -1.646428)
		(size 0.7112)
		(drill 0.4064)
		(layers "F.Cu" "B.Cu")
		(net "GND")
	)
	(via
		(at 121.998994 -53.543708)
		(size 0.7112)
		(drill 0.4064)
		(layers "F.Cu" "B.Cu")
		(net "GND")
	)
	(via
		(at 49.890426 -11.806428)
		(size 0.7112)
		(drill 0.4064)
		(layers "F.Cu" "B.Cu")
		(net "GND")
	)
	(via
		(at 65.379092 -62.721744)
		(size 0.7112)
		(drill 0.4064)
		(layers "F.Cu" "B.Cu")
		(net "GND")
	)
	(via
		(at 55.219092 -62.721744)
		(size 0.7112)
		(drill 0.4064)
		(layers "F.Cu" "B.Cu")
		(net "GND")
	)
	(via
		(at 50.139092 -52.434744)
		(size 0.7112)
		(drill 0.4064)
		(layers "F.Cu" "B.Cu")
		(net "GND")
	)
	(via
		(at 44.53382 -96.002856)
		(size 0.7112)
		(drill 0.4064)
		(layers "F.Cu" "B.Cu")
		(net "GND")
	)
	(via
		(at 156.464 -35.052)
		(size 0.7112)
		(drill 0.4064)
		(layers "F.Cu" "B.Cu")
		(net "GND")
	)
	(via
		(at 148.645626 -6.726428)
		(size 0.7112)
		(drill 0.4064)
		(layers "F.Cu" "B.Cu")
		(net "GND")
	)
	(via
		(at 45.059092 -57.641744)
		(size 0.7112)
		(drill 0.4064)
		(layers "F.Cu" "B.Cu")
		(net "GND")
	)
	(via
		(at 70.459092 -67.801744)
		(size 0.7112)
		(drill 0.4064)
		(layers "F.Cu" "B.Cu")
		(net "GND")
	)
	(via
		(at 115.1128 -51.2318)
		(size 0.7112)
		(drill 0.4064)
		(layers "F.Cu" "B.Cu")
		(net "GND")
	)
	(via
		(at 63.220092 -9.127744)
		(size 0.7112)
		(drill 0.3556)
		(layers "F.Cu" "B.Cu")
		(net "GND")
	)
	(via
		(at 85.699092 -62.721744)
		(size 0.7112)
		(drill 0.4064)
		(layers "F.Cu" "B.Cu")
		(net "GND")
	)
	(via
		(at 131.75869 -52.414678)
		(size 0.7112)
		(drill 0.4064)
		(layers "F.Cu" "B.Cu")
		(net "GND")
	)
	(via
		(at 95.610426 -11.806428)
		(size 0.7112)
		(drill 0.4064)
		(layers "F.Cu" "B.Cu")
		(net "GND")
	)
	(via
		(at 75.539092 -52.434744)
		(size 0.7112)
		(drill 0.4064)
		(layers "F.Cu" "B.Cu")
		(net "GND")
	)
	(via
		(at 17.22882 -118.227856)
		(size 0.7112)
		(drill 0.4064)
		(layers "F.Cu" "B.Cu")
		(net "GND")
	)
	(via
		(at 19.659092 -52.561744)
		(size 0.7112)
		(drill 0.4064)
		(layers "F.Cu" "B.Cu")
		(net "GND")
	)
	(via
		(at -0.748792 -76.759308)
		(size 0.7112)
		(drill 0.4064)
		(layers "F.Cu" "B.Cu")
		(net "GND")
	)
	(via
		(at 39.45382 -90.922856)
		(size 0.7112)
		(drill 0.4064)
		(layers "F.Cu" "B.Cu")
		(net "GND")
	)
	(via
		(at 80.09382 -96.002856)
		(size 0.7112)
		(drill 0.4064)
		(layers "F.Cu" "B.Cu")
		(net "GND")
	)
	(via
		(at 14.579092 -52.561744)
		(size 0.7112)
		(drill 0.4064)
		(layers "F.Cu" "B.Cu")
		(net "GND")
	)
	(via
		(at 135.096758 -53.438806)
		(size 0.7112)
		(drill 0.4064)
		(layers "F.Cu" "B.Cu")
		(net "GND")
	)
	(via
		(at 80.22082 -112.385856)
		(size 0.7112)
		(drill 0.4064)
		(layers "F.Cu" "B.Cu")
		(net "GND")
	)
	(via
		(at 135.096758 -52.372006)
		(size 0.7112)
		(drill 0.4064)
		(layers "F.Cu" "B.Cu")
		(net "GND")
	)
	(via
		(at 69.93382 -85.842856)
		(size 0.7112)
		(drill 0.4064)
		(layers "F.Cu" "B.Cu")
		(net "GND")
	)
	(via
		(at -0.660908 -70.341744)
		(size 0.7112)
		(drill 0.4064)
		(layers "F.Cu" "B.Cu")
		(net "GND")
	)
	(via
		(at 120.751092 -96.122744)
		(size 0.7112)
		(drill 0.4064)
		(layers "F.Cu" "B.Cu")
		(net "GND")
	)
	(via
		(at 4.170426 -1.646428)
		(size 0.7112)
		(drill 0.4064)
		(layers "F.Cu" "B.Cu")
		(net "GND")
	)
	(via
		(at 95.859092 -67.801744)
		(size 0.7112)
		(drill 0.4064)
		(layers "F.Cu" "B.Cu")
		(net "GND")
	)
	(via
		(at 21.67382 -112.512856)
		(size 0.7112)
		(drill 0.4064)
		(layers "F.Cu" "B.Cu")
		(net "GND")
	)
	(via
		(at 141.330426 -16.886428)
		(size 0.7112)
		(drill 0.4064)
		(layers "F.Cu" "B.Cu")
		(net "GND")
	)
	(via
		(at 44.577 -112.268)
		(size 0.7112)
		(drill 0.4064)
		(layers "F.Cu" "B.Cu")
		(net "GND")
	)
	(via
		(at 111.099092 -67.801744)
		(size 0.7112)
		(drill 0.4064)
		(layers "F.Cu" "B.Cu")
		(net "GND")
	)
	(via
		(at 80.619092 -72.881744)
		(size 0.7112)
		(drill 0.4064)
		(layers "F.Cu" "B.Cu")
		(net "GND")
	)
	(via
		(at 29.29382 -85.842856)
		(size 0.7112)
		(drill 0.4064)
		(layers "F.Cu" "B.Cu")
		(net "GND")
	)
	(via
		(at 110.617 -50.165)
		(size 0.7112)
		(drill 0.4064)
		(layers "F.Cu" "B.Cu")
		(net "GND")
	)
	(via
		(at 49.61382 -90.922856)
		(size 0.7112)
		(drill 0.4064)
		(layers "F.Cu" "B.Cu")
		(net "GND")
	)
	(via
		(at 135.864092 -66.404744)
		(size 0.7112)
		(drill 0.3556)
		(layers "F.Cu" "B.Cu")
		(net "GND")
	)
	(via
		(at 14.579092 -67.801744)
		(size 0.7112)
		(drill 0.4064)
		(layers "F.Cu" "B.Cu")
		(net "GND")
	)
	(via
		(at 19.659092 -57.641744)
		(size 0.7112)
		(drill 0.4064)
		(layers "F.Cu" "B.Cu")
		(net "GND")
	)
	(via
		(at 115.930426 -11.806428)
		(size 0.7112)
		(drill 0.4064)
		(layers "F.Cu" "B.Cu")
		(net "GND")
	)
	(via
		(at 55.219092 -57.641744)
		(size 0.7112)
		(drill 0.4064)
		(layers "F.Cu" "B.Cu")
		(net "GND")
	)
	(via
		(at 75.539092 -57.641744)
		(size 0.7112)
		(drill 0.4064)
		(layers "F.Cu" "B.Cu")
		(net "GND")
	)
	(via
		(at 95.33382 -90.922856)
		(size 0.7112)
		(drill 0.4064)
		(layers "F.Cu" "B.Cu")
		(net "GND")
	)
	(via
		(at 92.811092 -9.127744)
		(size 0.7112)
		(drill 0.3556)
		(layers "F.Cu" "B.Cu")
		(net "GND")
	)
	(via
		(at 125.199394 -52.476908)
		(size 0.7112)
		(drill 0.4064)
		(layers "F.Cu" "B.Cu")
		(net "GND")
	)
	(via
		(at 64.85382 -90.922856)
		(size 0.7112)
		(drill 0.4064)
		(layers "F.Cu" "B.Cu")
		(net "GND")
	)
	(via
		(at 54.69382 -90.922856)
		(size 0.7112)
		(drill 0.4064)
		(layers "F.Cu" "B.Cu")
		(net "GND")
	)
	(via
		(at 1.752092 -113.140744)
		(size 0.7112)
		(drill 0.4064)
		(layers "F.Cu" "B.Cu")
		(net "GND")
	)
	(via
		(at 121.180098 -50.030888)
		(size 0.7112)
		(drill 0.4064)
		(layers "F.Cu" "B.Cu")
		(net "GND")
	)
	(via
		(at 50.139092 -62.721744)
		(size 0.7112)
		(drill 0.4064)
		(layers "F.Cu" "B.Cu")
		(net "GND")
	)
	(via
		(at 100.939092 -72.881744)
		(size 0.7112)
		(drill 0.4064)
		(layers "F.Cu" "B.Cu")
		(net "GND")
	)
	(via
		(at 9.499092 -67.801744)
		(size 0.7112)
		(drill 0.4064)
		(layers "F.Cu" "B.Cu")
		(net "GND")
	)
	(via
		(at 109.5502 -51.2318)
		(size 0.7112)
		(drill 0.4064)
		(layers "F.Cu" "B.Cu")
		(net "GND")
	)
	(via
		(at 80.619092 -67.801744)
		(size 0.7112)
		(drill 0.4064)
		(layers "F.Cu" "B.Cu")
		(net "GND")
	)
	(via
		(at 121.259092 -57.641744)
		(size 0.7112)
		(drill 0.4064)
		(layers "F.Cu" "B.Cu")
		(net "GND")
	)
	(via
		(at 160.756092 -113.013744)
		(size 0.7112)
		(drill 0.4064)
		(layers "F.Cu" "B.Cu")
		(net "GND")
	)
	(via
		(at 9.499092 -72.881744)
		(size 0.7112)
		(drill 0.4064)
		(layers "F.Cu" "B.Cu")
		(net "GND")
	)
	(via
		(at 99.883214 -60.956952)
		(size 0.7112)
		(drill 0.3556)
		(layers "F.Cu" "B.Cu")
		(net "GND")
	)
	(via
		(at 105.770426 -6.726428)
		(size 0.7112)
		(drill 0.4064)
		(layers "F.Cu" "B.Cu")
		(net "GND")
	)
	(via
		(at 129.62509 -52.414678)
		(size 0.7112)
		(drill 0.4064)
		(layers "F.Cu" "B.Cu")
		(net "GND")
	)
	(via
		(at 95.46082 -112.385856)
		(size 0.7112)
		(drill 0.4064)
		(layers "F.Cu" "B.Cu")
		(net "GND")
	)
	(via
		(at 112.9792 -50.165)
		(size 0.7112)
		(drill 0.4064)
		(layers "F.Cu" "B.Cu")
		(net "GND")
	)
	(via
		(at 39.730426 -11.806428)
		(size 0.7112)
		(drill 0.4064)
		(layers "F.Cu" "B.Cu")
		(net "GND")
	)
	(via
		(at 106.273092 -67.801744)
		(size 0.7112)
		(drill 0.4064)
		(layers "F.Cu" "B.Cu")
		(net "GND")
	)
	(via
		(at 70.210426 -1.646428)
		(size 0.7112)
		(drill 0.4064)
		(layers "F.Cu" "B.Cu")
		(net "GND")
	)
	(via
		(at 9.250426 -6.726428)
		(size 0.7112)
		(drill 0.4064)
		(layers "F.Cu" "B.Cu")
		(net "GND")
	)
	(via
		(at 140.505434 -51.022758)
		(size 0.7112)
		(drill 0.4064)
		(layers "F.Cu" "B.Cu")
		(net "GND")
	)
	(via
		(at 60.299092 -57.641744)
		(size 0.7112)
		(drill 0.4064)
		(layers "F.Cu" "B.Cu")
		(net "GND")
	)
	(via
		(at 161.010092 -22.081744)
		(size 0.7112)
		(drill 0.4064)
		(layers "F.Cu" "B.Cu")
		(net "GND")
	)
	(via
		(at 139.438634 -49.955958)
		(size 0.7112)
		(drill 0.4064)
		(layers "F.Cu" "B.Cu")
		(net "GND")
	)
	(via
		(at 60.299092 -62.721744)
		(size 0.7112)
		(drill 0.4064)
		(layers "F.Cu" "B.Cu")
		(net "GND")
	)
	(via
		(at 160.756092 -107.933744)
		(size 0.7112)
		(drill 0.4064)
		(layers "F.Cu" "B.Cu")
		(net "GND")
	)
	(via
		(at 100.690426 -1.646428)
		(size 0.7112)
		(drill 0.4064)
		(layers "F.Cu" "B.Cu")
		(net "GND")
	)
	(via
		(at 70.210426 -6.726428)
		(size 0.7112)
		(drill 0.4064)
		(layers "F.Cu" "B.Cu")
		(net "GND")
	)
	(via
		(at 130.175 -82.042)
		(size 0.7112)
		(drill 0.4064)
		(layers "F.Cu" "B.Cu")
		(net "GND")
	)
	(via
		(at 65.379092 -57.641744)
		(size 0.7112)
		(drill 0.4064)
		(layers "F.Cu" "B.Cu")
		(net "GND")
	)
	(via
		(at 117.348 -50.165)
		(size 0.7112)
		(drill 0.4064)
		(layers "F.Cu" "B.Cu")
		(net "GND")
	)
	(via
		(at 80.09382 -85.842856)
		(size 0.7112)
		(drill 0.4064)
		(layers "F.Cu" "B.Cu")
		(net "GND")
	)
	(via
		(at 62.966092 -59.673744)
		(size 0.7112)
		(drill 0.3556)
		(layers "F.Cu" "B.Cu")
		(net "GND")
	)
	(via
		(at 85.17382 -96.002856)
		(size 0.7112)
		(drill 0.4064)
		(layers "F.Cu" "B.Cu")
		(net "GND")
	)
	(via
		(at 125.831092 -85.962744)
		(size 0.7112)
		(drill 0.4064)
		(layers "F.Cu" "B.Cu")
		(net "GND")
	)
	(via
		(at 55.219092 -52.434744)
		(size 0.7112)
		(drill 0.4064)
		(layers "F.Cu" "B.Cu")
		(net "GND")
	)
	(via
		(at 14.330426 -11.806428)
		(size 0.7112)
		(drill 0.4064)
		(layers "F.Cu" "B.Cu")
		(net "GND")
	)
	(via
		(at 80.370426 -6.726428)
		(size 0.7112)
		(drill 0.4064)
		(layers "F.Cu" "B.Cu")
		(net "GND")
	)
	(via
		(at 120.113298 -51.097688)
		(size 0.7112)
		(drill 0.4064)
		(layers "F.Cu" "B.Cu")
		(net "GND")
	)
	(via
		(at 60.050426 -6.726428)
		(size 0.7112)
		(drill 0.4064)
		(layers "F.Cu" "B.Cu")
		(net "GND")
	)
	(via
		(at 54.69382 -96.002856)
		(size 0.7112)
		(drill 0.4064)
		(layers "F.Cu" "B.Cu")
		(net "GND")
	)
	(via
		(at 153.014426 -1.646428)
		(size 0.7112)
		(drill 0.4064)
		(layers "F.Cu" "B.Cu")
		(net "GND")
	)
	(via
		(at 111.099092 -52.434744)
		(size 0.7112)
		(drill 0.4064)
		(layers "F.Cu" "B.Cu")
		(net "GND")
	)
	(via
		(at 10.134092 -118.220744)
		(size 0.7112)
		(drill 0.4064)
		(layers "F.Cu" "B.Cu")
		(net "GND")
	)
	(via
		(at 130.69189 -52.414678)
		(size 0.7112)
		(drill 0.4064)
		(layers "F.Cu" "B.Cu")
		(net "GND")
	)
	(via
		(at 75.01382 -85.842856)
		(size 0.7112)
		(drill 0.4064)
		(layers "F.Cu" "B.Cu")
		(net "GND")
	)
	(via
		(at 90.779092 -72.881744)
		(size 0.7112)
		(drill 0.4064)
		(layers "F.Cu" "B.Cu")
		(net "GND")
	)
	(via
		(at 152.4 -75.819)
		(size 0.7112)
		(drill 0.4064)
		(layers "F.Cu" "B.Cu")
		(net "GND")
	)
	(via
		(at 69.93382 -90.922856)
		(size 0.7112)
		(drill 0.4064)
		(layers "F.Cu" "B.Cu")
		(net "GND")
	)
	(via
		(at 55.219092 -72.881744)
		(size 0.7112)
		(drill 0.4064)
		(layers "F.Cu" "B.Cu")
		(net "GND")
	)
	(via
		(at 153.014426 -6.726428)
		(size 0.7112)
		(drill 0.4064)
		(layers "F.Cu" "B.Cu")
		(net "GND")
	)
	(via
		(at 39.730426 -1.646428)
		(size 0.7112)
		(drill 0.4064)
		(layers "F.Cu" "B.Cu")
		(net "GND")
	)
	(via
		(at 148.473922 -22.014434)
		(size 0.7112)
		(drill 0.4064)
		(layers "F.Cu" "B.Cu")
		(net "GND")
	)
	(via
		(at 124.968 -81.534)
		(size 0.7112)
		(drill 0.4064)
		(layers "F.Cu" "B.Cu")
		(net "GND")
	)
	(via
		(at 34.37382 -90.922856)
		(size 0.7112)
		(drill 0.4064)
		(layers "F.Cu" "B.Cu")
		(net "GND")
	)
	(via
		(at 144.276826 -11.806428)
		(size 0.7112)
		(drill 0.4064)
		(layers "F.Cu" "B.Cu")
		(net "GND")
	)
	(via
		(at 4.170426 -6.726428)
		(size 0.7112)
		(drill 0.4064)
		(layers "F.Cu" "B.Cu")
		(net "GND")
	)
	(via
		(at 9.250426 -1.646428)
		(size 0.7112)
		(drill 0.4064)
		(layers "F.Cu" "B.Cu")
		(net "GND")
	)
	(via
		(at 49.61382 -106.162856)
		(size 0.7112)
		(drill 0.4064)
		(layers "F.Cu" "B.Cu")
		(net "GND")
	)
	(via
		(at 116.179092 -52.434744)
		(size 0.7112)
		(drill 0.4064)
		(layers "F.Cu" "B.Cu")
		(net "GND")
	)
	(via
		(at 54.82082 -112.385856)
		(size 0.7112)
		(drill 0.4064)
		(layers "F.Cu" "B.Cu")
		(net "GND")
	)
	(via
		(at 50.139092 -67.801744)
		(size 0.7112)
		(drill 0.4064)
		(layers "F.Cu" "B.Cu")
		(net "GND")
	)
	(via
		(at 111.099092 -57.641744)
		(size 0.7112)
		(drill 0.4064)
		(layers "F.Cu" "B.Cu")
		(net "GND")
	)
	(via
		(at 19.913092 -91.042744)
		(size 0.7112)
		(drill 0.4064)
		(layers "F.Cu" "B.Cu")
		(net "GND")
	)
	(via
		(at 156.590492 -80.323944)
		(size 0.7112)
		(drill 0.4064)
		(layers "F.Cu" "B.Cu")
		(net "GND")
	)
	(via
		(at 125.199394 -53.543708)
		(size 0.7112)
		(drill 0.4064)
		(layers "F.Cu" "B.Cu")
		(net "GND")
	)
	(via
		(at 80.09382 -106.162856)
		(size 0.7112)
		(drill 0.4064)
		(layers "F.Cu" "B.Cu")
		(net "GND")
	)
	(via
		(at -0.660908 -62.721744)
		(size 0.7112)
		(drill 0.4064)
		(layers "F.Cu" "B.Cu")
		(net "GND")
	)
	(via
		(at 116.2812 -51.2318)
		(size 0.7112)
		(drill 0.4064)
		(layers "F.Cu" "B.Cu")
		(net "GND")
	)
	(via
		(at 15.748 -112.395)
		(size 0.7112)
		(drill 0.4064)
		(layers "F.Cu" "B.Cu")
		(net "GND")
	)
	(via
		(at 14.579092 -62.721744)
		(size 0.7112)
		(drill 0.4064)
		(layers "F.Cu" "B.Cu")
		(net "GND")
	)
	(via
		(at 19.659092 -72.881744)
		(size 0.7112)
		(drill 0.4064)
		(layers "F.Cu" "B.Cu")
		(net "GND")
	)
	(via
		(at 96.494092 -118.220744)
		(size 0.7112)
		(drill 0.4064)
		(layers "F.Cu" "B.Cu")
		(net "GND")
	)
	(via
		(at 64.85382 -96.002856)
		(size 0.7112)
		(drill 0.4064)
		(layers "F.Cu" "B.Cu")
		(net "GND")
	)
	(via
		(at 12.293092 -69.833744)
		(size 0.7112)
		(drill 0.3556)
		(layers "F.Cu" "B.Cu")
		(net "GND")
	)
	(via
		(at 49.890426 -1.646428)
		(size 0.7112)
		(drill 0.4064)
		(layers "F.Cu" "B.Cu")
		(net "GND")
	)
	(via
		(at 45.059092 -52.434744)
		(size 0.7112)
		(drill 0.4064)
		(layers "F.Cu" "B.Cu")
		(net "GND")
	)
	(via
		(at 111.6838 -50.165)
		(size 0.7112)
		(drill 0.4064)
		(layers "F.Cu" "B.Cu")
		(net "GND")
	)
	(via
		(at 6.959092 -67.801744)
		(size 0.7112)
		(drill 0.4064)
		(layers "F.Cu" "B.Cu")
		(net "GND")
	)
	(via
		(at 139.908026 -1.646428)
		(size 0.7112)
		(drill 0.4064)
		(layers "F.Cu" "B.Cu")
		(net "GND")
	)
	(via
		(at 150.368 -118.069614)
		(size 0.7112)
		(drill 0.4064)
		(layers "F.Cu" "B.Cu")
		(net "GND")
	)
	(via
		(at 35.534092 -118.220744)
		(size 0.7112)
		(drill 0.4064)
		(layers "F.Cu" "B.Cu")
		(net "GND")
	)
	(via
		(at 85.450426 -1.646428)
		(size 0.7112)
		(drill 0.4064)
		(layers "F.Cu" "B.Cu")
		(net "GND")
	)
	(via
		(at 60.299092 -52.434744)
		(size 0.7112)
		(drill 0.4064)
		(layers "F.Cu" "B.Cu")
		(net "GND")
	)
	(via
		(at 1.879092 -72.881744)
		(size 0.7112)
		(drill 0.4064)
		(layers "F.Cu" "B.Cu")
		(net "GND")
	)
	(via
		(at 134.051294 -49.893728)
		(size 0.7112)
		(drill 0.4064)
		(layers "F.Cu" "B.Cu")
		(net "GND")
	)
	(via
		(at 50.139092 -57.641744)
		(size 0.7112)
		(drill 0.4064)
		(layers "F.Cu" "B.Cu")
		(net "GND")
	)
	(via
		(at 157.383226 -11.806428)
		(size 0.7112)
		(drill 0.4064)
		(layers "F.Cu" "B.Cu")
		(net "GND")
	)
	(via
		(at 29.845 -118.237)
		(size 0.7112)
		(drill 0.4064)
		(layers "F.Cu" "B.Cu")
		(net "GND")
	)
	(via
		(at 19.786092 -85.962744)
		(size 0.7112)
		(drill 0.4064)
		(layers "F.Cu" "B.Cu")
		(net "GND")
	)
	(via
		(at 85.699092 -72.881744)
		(size 0.7112)
		(drill 0.4064)
		(layers "F.Cu" "B.Cu")
		(net "GND")
	)
	(via
		(at -0.660908 -55.101744)
		(size 0.7112)
		(drill 0.4064)
		(layers "F.Cu" "B.Cu")
		(net "GND")
	)
	(via
		(at 34.37382 -85.842856)
		(size 0.7112)
		(drill 0.4064)
		(layers "F.Cu" "B.Cu")
		(net "GND")
	)
	(via
		(at 95.610426 -6.726428)
		(size 0.7112)
		(drill 0.4064)
		(layers "F.Cu" "B.Cu")
		(net "GND")
	)
	(via
		(at 29.819092 -57.641744)
		(size 0.7112)
		(drill 0.4064)
		(layers "F.Cu" "B.Cu")
		(net "GND")
	)
	(via
		(at 45.059092 -62.721744)
		(size 0.7112)
		(drill 0.4064)
		(layers "F.Cu" "B.Cu")
		(net "GND")
	)
	(via
		(at 29.565092 -67.801744)
		(size 0.7112)
		(drill 0.4064)
		(layers "F.Cu" "B.Cu")
		(net "GND")
	)
	(via
		(at 9.10082 -112.385856)
		(size 0.7112)
		(drill 0.4064)
		(layers "F.Cu" "B.Cu")
		(net "GND")
	)
	(via
		(at 75.14082 -112.385856)
		(size 0.7112)
		(drill 0.4064)
		(layers "F.Cu" "B.Cu")
		(net "GND")
	)
	(via
		(at 1.879092 -62.721744)
		(size 0.7112)
		(drill 0.4064)
		(layers "F.Cu" "B.Cu")
		(net "GND")
	)
	(via
		(at 60.299092 -72.881744)
		(size 0.7112)
		(drill 0.4064)
		(layers "F.Cu" "B.Cu")
		(net "GND")
	)
	(via
		(at 120.751092 -85.962744)
		(size 0.7112)
		(drill 0.4064)
		(layers "F.Cu" "B.Cu")
		(net "GND")
	)
	(via
		(at 70.459092 -52.434744)
		(size 0.7112)
		(drill 0.4064)
		(layers "F.Cu" "B.Cu")
		(net "GND")
	)
	(via
		(at 24.21382 -96.002856)
		(size 0.7112)
		(drill 0.4064)
		(layers "F.Cu" "B.Cu")
		(net "GND")
	)
	(via
		(at 76.174092 -118.220744)
		(size 0.7112)
		(drill 0.4064)
		(layers "F.Cu" "B.Cu")
		(net "GND")
	)
	(via
		(at 24.739092 -72.881744)
		(size 0.7112)
		(drill 0.4064)
		(layers "F.Cu" "B.Cu")
		(net "GND")
	)
	(via
		(at 34.650426 -11.806428)
		(size 0.7112)
		(drill 0.4064)
		(layers "F.Cu" "B.Cu")
		(net "GND")
	)
	(via
		(at 54.69382 -106.162856)
		(size 0.7112)
		(drill 0.4064)
		(layers "F.Cu" "B.Cu")
		(net "GND")
	)
	(via
		(at 85.450426 -6.726428)
		(size 0.7112)
		(drill 0.4064)
		(layers "F.Cu" "B.Cu")
		(net "GND")
	)
	(via
		(at 69.93382 -106.162856)
		(size 0.7112)
		(drill 0.4064)
		(layers "F.Cu" "B.Cu")
		(net "GND")
	)
	(via
		(at 1.879092 -52.561744)
		(size 0.7112)
		(drill 0.4064)
		(layers "F.Cu" "B.Cu")
		(net "GND")
	)
	(via
		(at 90.25382 -96.002856)
		(size 0.7112)
		(drill 0.4064)
		(layers "F.Cu" "B.Cu")
		(net "GND")
	)
	(via
		(at 160.973262 -16.688054)
		(size 0.7112)
		(drill 0.4064)
		(layers "F.Cu" "B.Cu")
		(net "GND")
	)
	(via
		(at 14.579092 -57.641744)
		(size 0.7112)
		(drill 0.4064)
		(layers "F.Cu" "B.Cu")
		(net "GND")
	)
	(via
		(at 90.779092 -62.721744)
		(size 0.7112)
		(drill 0.4064)
		(layers "F.Cu" "B.Cu")
		(net "GND")
	)
	(via
		(at 132.176774 -76.392278)
		(size 0.7112)
		(drill 0.4064)
		(layers "F.Cu" "B.Cu")
		(net "GND")
	)
	(via
		(at 107.315 -51.2318)
		(size 0.7112)
		(drill 0.4064)
		(layers "F.Cu" "B.Cu")
		(net "GND")
	)
	(via
		(at 161.066226 -6.726428)
		(size 0.7112)
		(drill 0.4064)
		(layers "F.Cu" "B.Cu")
		(net "GND")
	)
	(via
		(at 156.311092 -72.246744)
		(size 0.7112)
		(drill 0.4064)
		(layers "F.Cu" "B.Cu")
		(net "GND")
	)
	(via
		(at 136.163558 -53.438806)
		(size 0.7112)
		(drill 0.4064)
		(layers "F.Cu" "B.Cu")
		(net "GND")
	)
	(via
		(at 24.739092 -62.721744)
		(size 0.7112)
		(drill 0.4064)
		(layers "F.Cu" "B.Cu")
		(net "GND")
	)
	(via
		(at 49.890426 -6.726428)
		(size 0.7112)
		(drill 0.4064)
		(layers "F.Cu" "B.Cu")
		(net "GND")
	)
	(via
		(at 142.367 -68.072)
		(size 0.7112)
		(drill 0.4064)
		(layers "F.Cu" "B.Cu")
		(net "GND")
	)
	(via
		(at 106.019092 -62.721744)
		(size 0.7112)
		(drill 0.4064)
		(layers "F.Cu" "B.Cu")
		(net "GND")
	)
	(via
		(at 111.6838 -51.2318)
		(size 0.7112)
		(drill 0.4064)
		(layers "F.Cu" "B.Cu")
		(net "GND")
	)
	(via
		(at 60.299092 -67.801744)
		(size 0.7112)
		(drill 0.4064)
		(layers "F.Cu" "B.Cu")
		(net "GND")
	)
	(via
		(at 90.779092 -67.801744)
		(size 0.7112)
		(drill 0.4064)
		(layers "F.Cu" "B.Cu")
		(net "GND")
	)
	(via
		(at 136.652 -118.069614)
		(size 0.7112)
		(drill 0.4064)
		(layers "F.Cu" "B.Cu")
		(net "GND")
	)
	(via
		(at -1.803908 -85.649308)
		(size 0.7112)
		(drill 0.4064)
		(layers "F.Cu" "B.Cu")
		(net "GND")
	)
	(via
		(at 116.179092 -57.641744)
		(size 0.7112)
		(drill 0.4064)
		(layers "F.Cu" "B.Cu")
		(net "GND")
	)
	(via
		(at 156.464 -29.337)
		(size 0.7112)
		(drill 0.4064)
		(layers "F.Cu" "B.Cu")
		(net "GND")
	)
	(via
		(at 100.690426 -11.806428)
		(size 0.7112)
		(drill 0.4064)
		(layers "F.Cu" "B.Cu")
		(net "GND")
	)
	(via
		(at 34.650426 -1.646428)
		(size 0.7112)
		(drill 0.4064)
		(layers "F.Cu" "B.Cu")
		(net "GND")
	)
	(via
		(at 138.8364 -65.524634)
		(size 0.7112)
		(drill 0.4064)
		(layers "F.Cu" "B.Cu")
		(net "GND")
	)
	(via
		(at 110.591092 -96.122744)
		(size 0.7112)
		(drill 0.4064)
		(layers "F.Cu" "B.Cu")
		(net "GND")
	)
	(via
		(at 125.831092 -96.122744)
		(size 0.7112)
		(drill 0.4064)
		(layers "F.Cu" "B.Cu")
		(net "GND")
	)
	(via
		(at 17.119092 -105.901744)
		(size 0.7112)
		(drill 0.3556)
		(layers "F.Cu" "B.Cu")
		(net "GND")
	)
	(via
		(at 50.139092 -72.881744)
		(size 0.7112)
		(drill 0.4064)
		(layers "F.Cu" "B.Cu")
		(net "GND")
	)
	(via
		(at 114.046 -50.165)
		(size 0.7112)
		(drill 0.4064)
		(layers "F.Cu" "B.Cu")
		(net "GND")
	)
	(via
		(at 39.979092 -57.641744)
		(size 0.7112)
		(drill 0.4064)
		(layers "F.Cu" "B.Cu")
		(net "GND")
	)
	(via
		(at 29.819092 -52.561744)
		(size 0.7112)
		(drill 0.4064)
		(layers "F.Cu" "B.Cu")
		(net "GND")
	)
	(via
		(at 135.539226 -6.726428)
		(size 0.7112)
		(drill 0.4064)
		(layers "F.Cu" "B.Cu")
		(net "GND")
	)
	(via
		(at 128.879092 -49.894744)
		(size 0.7112)
		(drill 0.3556)
		(layers "F.Cu" "B.Cu")
		(net "GND")
	)
	(via
		(at 106.654092 -118.220744)
		(size 0.7112)
		(drill 0.4064)
		(layers "F.Cu" "B.Cu")
		(net "GND")
	)
	(via
		(at 144.276826 -1.646428)
		(size 0.7112)
		(drill 0.4064)
		(layers "F.Cu" "B.Cu")
		(net "GND")
	)
	(via
		(at 110.850426 -1.646428)
		(size 0.7112)
		(drill 0.4064)
		(layers "F.Cu" "B.Cu")
		(net "GND")
	)
	(via
		(at 100.939092 -52.434744)
		(size 0.7112)
		(drill 0.4064)
		(layers "F.Cu" "B.Cu")
		(net "GND")
	)
	(via
		(at 80.619092 -57.641744)
		(size 0.7112)
		(drill 0.4064)
		(layers "F.Cu" "B.Cu")
		(net "GND")
	)
	(via
		(at 34.899092 -57.641744)
		(size 0.7112)
		(drill 0.4064)
		(layers "F.Cu" "B.Cu")
		(net "GND")
	)
	(via
		(at 110.591092 -85.962744)
		(size 0.7112)
		(drill 0.4064)
		(layers "F.Cu" "B.Cu")
		(net "GND")
	)
	(via
		(at 1.879092 -60.181744)
		(size 0.7112)
		(drill 0.4064)
		(layers "F.Cu" "B.Cu")
		(net "GND")
	)
	(via
		(at 86.334092 -118.220744)
		(size 0.7112)
		(drill 0.4064)
		(layers "F.Cu" "B.Cu")
		(net "GND")
	)
	(via
		(at 142.238984 -71.874888)
		(size 0.7112)
		(drill 0.4064)
		(layers "F.Cu" "B.Cu")
		(net "GND")
	)
	(via
		(at 29.565092 -72.881744)
		(size 0.7112)
		(drill 0.4064)
		(layers "F.Cu" "B.Cu")
		(net "GND")
	)
	(via
		(at 116.179092 -67.801744)
		(size 0.7112)
		(drill 0.4064)
		(layers "F.Cu" "B.Cu")
		(net "GND")
	)
	(via
		(at 90.530426 -6.726428)
		(size 0.7112)
		(drill 0.4064)
		(layers "F.Cu" "B.Cu")
		(net "GND")
	)
	(via
		(at 75.01382 -90.922856)
		(size 0.7112)
		(drill 0.4064)
		(layers "F.Cu" "B.Cu")
		(net "GND")
	)
	(via
		(at 160.02 -87.757)
		(size 0.7112)
		(drill 0.4064)
		(layers "F.Cu" "B.Cu")
		(net "GND")
	)
	(via
		(at 130.69189 -53.481478)
		(size 0.7112)
		(drill 0.4064)
		(layers "F.Cu" "B.Cu")
		(net "GND")
	)
	(via
		(at 5.054092 -118.220744)
		(size 0.7112)
		(drill 0.4064)
		(layers "F.Cu" "B.Cu")
		(net "GND")
	)
	(via
		(at 75.01382 -96.002856)
		(size 0.7112)
		(drill 0.4064)
		(layers "F.Cu" "B.Cu")
		(net "GND")
	)
	(via
		(at 85.17382 -85.842856)
		(size 0.7112)
		(drill 0.4064)
		(layers "F.Cu" "B.Cu")
		(net "GND")
	)
	(via
		(at 106.019092 -57.641744)
		(size 0.7112)
		(drill 0.4064)
		(layers "F.Cu" "B.Cu")
		(net "GND")
	)
	(via
		(at 151.003 -29.718)
		(size 0.7112)
		(drill 0.4064)
		(layers "F.Cu" "B.Cu")
		(net "GND")
	)
	(via
		(at 159.639 -26.416)
		(size 0.7112)
		(drill 0.4064)
		(layers "F.Cu" "B.Cu")
		(net "GND")
	)
	(via
		(at 70.967092 -72.881744)
		(size 0.7112)
		(drill 0.4064)
		(layers "F.Cu" "B.Cu")
		(net "GND")
	)
	(via
		(at 105.770426 -1.646428)
		(size 0.7112)
		(drill 0.4064)
		(layers "F.Cu" "B.Cu")
		(net "GND")
	)
	(via
		(at 138.297158 -52.372006)
		(size 0.7112)
		(drill 0.4064)
		(layers "F.Cu" "B.Cu")
		(net "GND")
	)
	(via
		(at 44.53382 -85.842856)
		(size 0.7112)
		(drill 0.4064)
		(layers "F.Cu" "B.Cu")
		(net "GND")
	)
	(via
		(at 39.37 -112.268)
		(size 0.7112)
		(drill 0.4064)
		(layers "F.Cu" "B.Cu")
		(net "GND")
	)
	(via
		(at 19.177 -106.045)
		(size 0.7112)
		(drill 0.4064)
		(layers "F.Cu" "B.Cu")
		(net "GND")
	)
	(via
		(at 144.399 -118.069614)
		(size 0.7112)
		(drill 0.4064)
		(layers "F.Cu" "B.Cu")
		(net "GND")
	)
	(via
		(at 123.065794 -52.476908)
		(size 0.7112)
		(drill 0.4064)
		(layers "F.Cu" "B.Cu")
		(net "GND")
	)
	(via
		(at 161.066226 -1.646428)
		(size 0.7112)
		(drill 0.4064)
		(layers "F.Cu" "B.Cu")
		(net "GND")
	)
	(via
		(at 24.739092 -67.801744)
		(size 0.7112)
		(drill 0.4064)
		(layers "F.Cu" "B.Cu")
		(net "GND")
	)
	(via
		(at 9.339326 -57.641744)
		(size 0.7112)
		(drill 0.4064)
		(layers "F.Cu" "B.Cu")
		(net "GND")
	)
	(via
		(at 125.831092 -91.042744)
		(size 0.7112)
		(drill 0.4064)
		(layers "F.Cu" "B.Cu")
		(net "GND")
	)
	(via
		(at 110.57382 -106.162856)
		(size 0.7112)
		(drill 0.4064)
		(layers "F.Cu" "B.Cu")
		(net "GND")
	)
	(via
		(at 90.25382 -85.842856)
		(size 0.7112)
		(drill 0.4064)
		(layers "F.Cu" "B.Cu")
		(net "GND")
	)
	(via
		(at 157.383226 -6.726428)
		(size 0.7112)
		(drill 0.4064)
		(layers "F.Cu" "B.Cu")
		(net "GND")
	)
	(via
		(at 1.625092 -93.963744)
		(size 0.7112)
		(drill 0.4064)
		(layers "F.Cu" "B.Cu")
		(net "GND")
	)
	(via
		(at -1.676908 -90.729308)
		(size 0.7112)
		(drill 0.4064)
		(layers "F.Cu" "B.Cu")
		(net "GND")
	)
	(via
		(at -1.676908 -88.189308)
		(size 0.7112)
		(drill 0.4064)
		(layers "F.Cu" "B.Cu")
		(net "GND")
	)
	(via
		(at 156.337 -50.546)
		(size 0.7112)
		(drill 0.4064)
		(layers "F.Cu" "B.Cu")
		(net "GND")
	)
	(via
		(at 70.459092 -62.721744)
		(size 0.7112)
		(drill 0.4064)
		(layers "F.Cu" "B.Cu")
		(net "GND")
	)
	(via
		(at 137.230358 -52.372006)
		(size 0.7112)
		(drill 0.4064)
		(layers "F.Cu" "B.Cu")
		(net "GND")
	)
	(via
		(at 1.752092 -98.408744)
		(size 0.7112)
		(drill 0.4064)
		(layers "F.Cu" "B.Cu")
		(net "GND")
	)
	(via
		(at 40.614092 -118.220744)
		(size 0.7112)
		(drill 0.4064)
		(layers "F.Cu" "B.Cu")
		(net "GND")
	)
	(via
		(at 8.632444 -92.184982)
		(size 0.7112)
		(drill 0.4064)
		(layers "F.Cu" "B.Cu")
		(net "GND")
	)
	(via
		(at 39.979092 -52.561744)
		(size 0.7112)
		(drill 0.4064)
		(layers "F.Cu" "B.Cu")
		(net "GND")
	)
	(via
		(at -0.660908 -52.561744)
		(size 0.7112)
		(drill 0.4064)
		(layers "F.Cu" "B.Cu")
		(net "GND")
	)
	(via
		(at 12.039092 -54.593744)
		(size 0.7112)
		(drill 0.3556)
		(layers "F.Cu" "B.Cu")
		(net "GND")
	)
	(via
		(at 29.29382 -96.002856)
		(size 0.7112)
		(drill 0.4064)
		(layers "F.Cu" "B.Cu")
		(net "GND")
	)
	(via
		(at 126.505208 -50.898806)
		(size 0.7112)
		(drill 0.4064)
		(layers "F.Cu" "B.Cu")
		(net "GND")
	)
	(via
		(at 75.290426 -11.806428)
		(size 0.7112)
		(drill 0.4064)
		(layers "F.Cu" "B.Cu")
		(net "GND")
	)
	(via
		(at 44.810426 -1.646428)
		(size 0.7112)
		(drill 0.4064)
		(layers "F.Cu" "B.Cu")
		(net "GND")
	)
	(via
		(at 4.419092 -65.261744)
		(size 0.7112)
		(drill 0.4064)
		(layers "F.Cu" "B.Cu")
		(net "GND")
	)
	(via
		(at 126.339092 -62.721744)
		(size 0.7112)
		(drill 0.4064)
		(layers "F.Cu" "B.Cu")
		(net "GND")
	)
	(via
		(at 59.77382 -106.162856)
		(size 0.7112)
		(drill 0.4064)
		(layers "F.Cu" "B.Cu")
		(net "GND")
	)
	(via
		(at 121.180098 -51.097688)
		(size 0.7112)
		(drill 0.4064)
		(layers "F.Cu" "B.Cu")
		(net "GND")
	)
	(via
		(at 121.259092 -62.721744)
		(size 0.7112)
		(drill 0.4064)
		(layers "F.Cu" "B.Cu")
		(net "GND")
	)
	(via
		(at 111.099092 -62.721744)
		(size 0.7112)
		(drill 0.4064)
		(layers "F.Cu" "B.Cu")
		(net "GND")
	)
	(via
		(at -0.660908 -57.641744)
		(size 0.7112)
		(drill 0.4064)
		(layers "F.Cu" "B.Cu")
		(net "GND")
	)
	(via
		(at 142.621 -75.692)
		(size 0.7112)
		(drill 0.4064)
		(layers "F.Cu" "B.Cu")
		(net "GND")
	)
	(via
		(at 6.477 -89.662)
		(size 0.7112)
		(drill 0.4064)
		(layers "F.Cu" "B.Cu")
		(net "GND")
	)
	(via
		(at 109.5502 -50.165)
		(size 0.7112)
		(drill 0.4064)
		(layers "F.Cu" "B.Cu")
		(net "GND")
	)
	(via
		(at 39.45382 -85.842856)
		(size 0.7112)
		(drill 0.4064)
		(layers "F.Cu" "B.Cu")
		(net "GND")
	)
	(via
		(at 34.899092 -72.881744)
		(size 0.7112)
		(drill 0.4064)
		(layers "F.Cu" "B.Cu")
		(net "GND")
	)
	(via
		(at 19.304 -8.128)
		(size 0.7112)
		(drill 0.3556)
		(layers "F.Cu" "B.Cu")
		(net "GND")
	)
	(via
		(at 148.645626 -1.646428)
		(size 0.7112)
		(drill 0.4064)
		(layers "F.Cu" "B.Cu")
		(net "GND")
	)
	(via
		(at 85.699092 -67.801744)
		(size 0.7112)
		(drill 0.4064)
		(layers "F.Cu" "B.Cu")
		(net "GND")
	)
	(via
		(at 60.050426 -11.806428)
		(size 0.7112)
		(drill 0.4064)
		(layers "F.Cu" "B.Cu")
		(net "GND")
	)
	(via
		(at 129.62509 -53.481478)
		(size 0.7112)
		(drill 0.4064)
		(layers "F.Cu" "B.Cu")
		(net "GND")
	)
	(via
		(at 139.438634 -51.022758)
		(size 0.7112)
		(drill 0.4064)
		(layers "F.Cu" "B.Cu")
		(net "GND")
	)
	(via
		(at 70.459092 -57.641744)
		(size 0.7112)
		(drill 0.4064)
		(layers "F.Cu" "B.Cu")
		(net "GND")
	)
	(via
		(at 80.619092 -62.721744)
		(size 0.7112)
		(drill 0.4064)
		(layers "F.Cu" "B.Cu")
		(net "GND")
	)
	(via
		(at 138.297158 -53.438806)
		(size 0.7112)
		(drill 0.4064)
		(layers "F.Cu" "B.Cu")
		(net "GND")
	)
	(via
		(at 80.370426 -1.646428)
		(size 0.7112)
		(drill 0.4064)
		(layers "F.Cu" "B.Cu")
		(net "GND")
	)
	(via
		(at 106.2482 -51.2318)
		(size 0.7112)
		(drill 0.4064)
		(layers "F.Cu" "B.Cu")
		(net "GND")
	)
	(via
		(at 6.959092 -52.561744)
		(size 0.7112)
		(drill 0.4064)
		(layers "F.Cu" "B.Cu")
		(net "GND")
	)
	(via
		(at 5.588 -98.425)
		(size 0.7112)
		(drill 0.4064)
		(layers "F.Cu" "B.Cu")
		(net "GND")
	)
	(via
		(at 95.33382 -106.162856)
		(size 0.7112)
		(drill 0.4064)
		(layers "F.Cu" "B.Cu")
		(net "GND")
	)
	(via
		(at 5.588 -95.123)
		(size 0.7112)
		(drill 0.4064)
		(layers "F.Cu" "B.Cu")
		(net "GND")
	)
	(via
		(at 116.179092 -72.881744)
		(size 0.7112)
		(drill 0.4064)
		(layers "F.Cu" "B.Cu")
		(net "GND")
	)
	(via
		(at 112.903 -113.03)
		(size 0.7112)
		(drill 0.3556)
		(layers "F.Cu" "B.Cu")
		(net "GND")
	)
	(via
		(at 114.046 -51.2318)
		(size 0.7112)
		(drill 0.4064)
		(layers "F.Cu" "B.Cu")
		(net "GND")
	)
	(via
		(at 80.370426 -11.806428)
		(size 0.7112)
		(drill 0.4064)
		(layers "F.Cu" "B.Cu")
		(net "GND")
	)
	(via
		(at 81.254092 -118.220744)
		(size 0.7112)
		(drill 0.4064)
		(layers "F.Cu" "B.Cu")
		(net "GND")
	)
	(via
		(at 76.301092 -72.881744)
		(size 0.7112)
		(drill 0.4064)
		(layers "F.Cu" "B.Cu")
		(net "GND")
	)
	(via
		(at 159.131 -19.939)
		(size 0.7112)
		(drill 0.4064)
		(layers "F.Cu" "B.Cu")
		(net "GND")
	)
	(via
		(at 65.379092 -67.801744)
		(size 0.7112)
		(drill 0.4064)
		(layers "F.Cu" "B.Cu")
		(net "GND")
	)
	(via
		(at 6.959092 -55.101744)
		(size 0.7112)
		(drill 0.4064)
		(layers "F.Cu" "B.Cu")
		(net "GND")
	)
	(via
		(at 24.21382 -106.162856)
		(size 0.7112)
		(drill 0.4064)
		(layers "F.Cu" "B.Cu")
		(net "GND")
	)
	(via
		(at 4.419092 -67.801744)
		(size 0.7112)
		(drill 0.4064)
		(layers "F.Cu" "B.Cu")
		(net "GND")
	)
	(via
		(at 135.636 -71.628)
		(size 0.7112)
		(drill 0.4064)
		(layers "F.Cu" "B.Cu")
		(net "GND")
	)
	(via
		(at 1.879092 -65.261744)
		(size 0.7112)
		(drill 0.4064)
		(layers "F.Cu" "B.Cu")
		(net "GND")
	)
	(via
		(at 101.574092 -118.220744)
		(size 0.7112)
		(drill 0.4064)
		(layers "F.Cu" "B.Cu")
		(net "GND")
	)
	(via
		(at 100.54082 -112.385856)
		(size 0.7112)
		(drill 0.4064)
		(layers "F.Cu" "B.Cu")
		(net "GND")
	)
	(via
		(at 45.694092 -118.220744)
		(size 0.7112)
		(drill 0.4064)
		(layers "F.Cu" "B.Cu")
		(net "GND")
	)
	(via
		(at 34.37382 -106.162856)
		(size 0.7112)
		(drill 0.4064)
		(layers "F.Cu" "B.Cu")
		(net "GND")
	)
	(via
		(at 54.970426 -6.726428)
		(size 0.7112)
		(drill 0.4064)
		(layers "F.Cu" "B.Cu")
		(net "GND")
	)
	(via
		(at 1.879092 -67.801744)
		(size 0.7112)
		(drill 0.4064)
		(layers "F.Cu" "B.Cu")
		(net "GND")
	)
	(via
		(at 139.192 -112.395)
		(size 0.7112)
		(drill 0.4064)
		(layers "F.Cu" "B.Cu")
		(net "GND")
	)
	(via
		(at 29.570426 -11.806428)
		(size 0.7112)
		(drill 0.4064)
		(layers "F.Cu" "B.Cu")
		(net "GND")
	)
	(via
		(at 34.37382 -96.002856)
		(size 0.7112)
		(drill 0.4064)
		(layers "F.Cu" "B.Cu")
		(net "GND")
	)
	(via
		(at 49.61382 -85.842856)
		(size 0.7112)
		(drill 0.4064)
		(layers "F.Cu" "B.Cu")
		(net "GND")
	)
	(via
		(at 100.41382 -85.842856)
		(size 0.7112)
		(drill 0.4064)
		(layers "F.Cu" "B.Cu")
		(net "GND")
	)
	(via
		(at 116.2812 -50.165)
		(size 0.7112)
		(drill 0.4064)
		(layers "F.Cu" "B.Cu")
		(net "GND")
	)
	(via
		(at 14.579092 -72.881744)
		(size 0.7112)
		(drill 0.4064)
		(layers "F.Cu" "B.Cu")
		(net "GND")
	)
	(via
		(at 1.879092 -57.641744)
		(size 0.7112)
		(drill 0.4064)
		(layers "F.Cu" "B.Cu")
		(net "GND")
	)
	(via
		(at 156.438092 -57.006744)
		(size 0.7112)
		(drill 0.4064)
		(layers "F.Cu" "B.Cu")
		(net "GND")
	)
	(via
		(at 124.132594 -53.543708)
		(size 0.7112)
		(drill 0.4064)
		(layers "F.Cu" "B.Cu")
		(net "GND")
	)
	(via
		(at -0.660908 -80.374744)
		(size 0.7112)
		(drill 0.4064)
		(layers "F.Cu" "B.Cu")
		(net "GND")
	)
	(via
		(at 128.651 -106.299)
		(size 0.7112)
		(drill 0.3556)
		(layers "F.Cu" "B.Cu")
		(net "GND")
	)
	(via
		(at 4.419092 -70.341744)
		(size 0.7112)
		(drill 0.4064)
		(layers "F.Cu" "B.Cu")
		(net "GND")
	)
	(via
		(at 29.819092 -62.721744)
		(size 0.7112)
		(drill 0.4064)
		(layers "F.Cu" "B.Cu")
		(net "GND")
	)
	(via
		(at 49.784 -112.395)
		(size 0.7112)
		(drill 0.4064)
		(layers "F.Cu" "B.Cu")
		(net "GND")
	)
	(via
		(at 115.671092 -96.122744)
		(size 0.7112)
		(drill 0.4064)
		(layers "F.Cu" "B.Cu")
		(net "GND")
	)
	(via
		(at 118.491 -108.712)
		(size 0.7112)
		(drill 0.4064)
		(layers "F.Cu" "B.Cu")
		(net "GND")
	)
	(via
		(at 65.130426 -11.806428)
		(size 0.7112)
		(drill 0.4064)
		(layers "F.Cu" "B.Cu")
		(net "GND")
	)
	(via
		(at 100.690426 -6.726428)
		(size 0.7112)
		(drill 0.4064)
		(layers "F.Cu" "B.Cu")
		(net "GND")
	)
	(via
		(at 16.357092 -77.326744)
		(size 0.7112)
		(drill 0.4064)
		(layers "F.Cu" "B.Cu")
		(net "GND")
	)
	(via
		(at 155.168092 -108.060744)
		(size 0.7112)
		(drill 0.4064)
		(layers "F.Cu" "B.Cu")
		(net "GND")
	)
	(via
		(at 155.168092 -113.140744)
		(size 0.7112)
		(drill 0.4064)
		(layers "F.Cu" "B.Cu")
		(net "GND")
	)
	(via
		(at 69.93382 -96.002856)
		(size 0.7112)
		(drill 0.4064)
		(layers "F.Cu" "B.Cu")
		(net "GND")
	)
	(via
		(at 115.65382 -106.162856)
		(size 0.7112)
		(drill 0.4064)
		(layers "F.Cu" "B.Cu")
		(net "GND")
	)
	(via
		(at 126.505208 -49.832006)
		(size 0.7112)
		(drill 0.4064)
		(layers "F.Cu" "B.Cu")
		(net "GND")
	)
	(via
		(at 127.572008 -49.832006)
		(size 0.7112)
		(drill 0.4064)
		(layers "F.Cu" "B.Cu")
		(net "GND")
	)
	(via
		(at 39.979092 -62.721744)
		(size 0.7112)
		(drill 0.4064)
		(layers "F.Cu" "B.Cu")
		(net "GND")
	)
	(via
		(at 132.984494 -49.893728)
		(size 0.7112)
		(drill 0.4064)
		(layers "F.Cu" "B.Cu")
		(net "GND")
	)
	(via
		(at 50.774092 -118.220744)
		(size 0.7112)
		(drill 0.4064)
		(layers "F.Cu" "B.Cu")
		(net "GND")
	)
	(via
		(at 155.168092 -118.220744)
		(size 0.7112)
		(drill 0.4064)
		(layers "F.Cu" "B.Cu")
		(net "GND")
	)
	(via
		(at 64.98082 -112.385856)
		(size 0.7112)
		(drill 0.4064)
		(layers "F.Cu" "B.Cu")
		(net "GND")
	)
	(via
		(at 85.17382 -90.922856)
		(size 0.7112)
		(drill 0.4064)
		(layers "F.Cu" "B.Cu")
		(net "GND")
	)
	(via
		(at 139.908026 -6.726428)
		(size 0.7112)
		(drill 0.4064)
		(layers "F.Cu" "B.Cu")
		(net "GND")
	)
	(via
		(at 161.036 -31.369)
		(size 0.7112)
		(drill 0.4064)
		(layers "F.Cu" "B.Cu")
		(net "GND")
	)
	(via
		(at 134.051294 -50.960528)
		(size 0.7112)
		(drill 0.4064)
		(layers "F.Cu" "B.Cu")
		(net "GND")
	)
	(via
		(at 26.75382 -112.512856)
		(size 0.7112)
		(drill 0.4064)
		(layers "F.Cu" "B.Cu")
		(net "GND")
	)
	(via
		(at 75.539092 -62.721744)
		(size 0.7112)
		(drill 0.4064)
		(layers "F.Cu" "B.Cu")
		(net "GND")
	)
	(via
		(at 126.339092 -57.641744)
		(size 0.7112)
		(drill 0.4064)
		(layers "F.Cu" "B.Cu")
		(net "GND")
	)
	(via
		(at 19.659092 -67.801744)
		(size 0.7112)
		(drill 0.4064)
		(layers "F.Cu" "B.Cu")
		(net "GND")
	)
	(via
		(at 128.651 -77.597)
		(size 0.7112)
		(drill 0.4064)
		(layers "F.Cu" "B.Cu")
		(net "GND")
	)
	(via
		(at 19.410426 -11.806428)
		(size 0.7112)
		(drill 0.4064)
		(layers "F.Cu" "B.Cu")
		(net "GND")
	)
	(via
		(at 75.290426 -6.726428)
		(size 0.7112)
		(drill 0.4064)
		(layers "F.Cu" "B.Cu")
		(net "GND")
	)
	(via
		(at 21.945092 -77.199744)
		(size 0.7112)
		(drill 0.4064)
		(layers "F.Cu" "B.Cu")
		(net "GND")
	)
	(via
		(at 24.21382 -90.922856)
		(size 0.7112)
		(drill 0.4064)
		(layers "F.Cu" "B.Cu")
		(net "GND")
	)
	(via
		(at 100.41382 -90.922856)
		(size 0.7112)
		(drill 0.4064)
		(layers "F.Cu" "B.Cu")
		(net "GND")
	)
	(via
		(at 75.01382 -106.162856)
		(size 0.7112)
		(drill 0.4064)
		(layers "F.Cu" "B.Cu")
		(net "GND")
	)
	(via
		(at 144.276826 -6.726428)
		(size 0.7112)
		(drill 0.4064)
		(layers "F.Cu" "B.Cu")
		(net "GND")
	)
	(via
		(at 44.810426 -6.726428)
		(size 0.7112)
		(drill 0.4064)
		(layers "F.Cu" "B.Cu")
		(net "GND")
	)
	(via
		(at -0.660908 -60.181744)
		(size 0.7112)
		(drill 0.4064)
		(layers "F.Cu" "B.Cu")
		(net "GND")
	)
	(via
		(at 105.49382 -85.842856)
		(size 0.7112)
		(drill 0.4064)
		(layers "F.Cu" "B.Cu")
		(net "GND")
	)
	(via
		(at 90.25382 -90.922856)
		(size 0.7112)
		(drill 0.4064)
		(layers "F.Cu" "B.Cu")
		(net "GND")
	)
	(via
		(at 131.170426 -1.646428)
		(size 0.7112)
		(drill 0.4064)
		(layers "F.Cu" "B.Cu")
		(net "GND")
	)
	(via
		(at 45.059092 -72.881744)
		(size 0.7112)
		(drill 0.4064)
		(layers "F.Cu" "B.Cu")
		(net "GND")
	)
	(via
		(at 39.979092 -72.881744)
		(size 0.7112)
		(drill 0.4064)
		(layers "F.Cu" "B.Cu")
		(net "GND")
	)
	(via
		(at 59.77382 -90.922856)
		(size 0.7112)
		(drill 0.4064)
		(layers "F.Cu" "B.Cu")
		(net "GND")
	)
	(via
		(at 160.756092 -118.093744)
		(size 0.7112)
		(drill 0.4064)
		(layers "F.Cu" "B.Cu")
		(net "GND")
	)
	(via
		(at 95.859092 -62.721744)
		(size 0.7112)
		(drill 0.4064)
		(layers "F.Cu" "B.Cu")
		(net "GND")
	)
	(via
		(at 85.699092 -52.434744)
		(size 0.7112)
		(drill 0.4064)
		(layers "F.Cu" "B.Cu")
		(net "GND")
	)
	(via
		(at 85.17382 -106.162856)
		(size 0.7112)
		(drill 0.4064)
		(layers "F.Cu" "B.Cu")
		(net "GND")
	)
	(via
		(at 71.729092 -79.358744)
		(size 0.7112)
		(drill 0.3556)
		(layers "F.Cu" "B.Cu")
		(net "GND")
	)
	(via
		(at 19.913092 -94.471744)
		(size 0.7112)
		(drill 0.3556)
		(layers "F.Cu" "B.Cu")
		(net "GND")
	)
	(via
		(at 4.419092 -55.101744)
		(size 0.7112)
		(drill 0.4064)
		(layers "F.Cu" "B.Cu")
		(net "GND")
	)
	(via
		(at 39.45382 -106.162856)
		(size 0.7112)
		(drill 0.4064)
		(layers "F.Cu" "B.Cu")
		(net "GND")
	)
	(via
		(at 126.090426 -11.806428)
		(size 0.7112)
		(drill 0.4064)
		(layers "F.Cu" "B.Cu")
		(net "GND")
	)
	(via
		(at 121.259092 -67.801744)
		(size 0.7112)
		(drill 0.4064)
		(layers "F.Cu" "B.Cu")
		(net "GND")
	)
	(via
		(at 90.530426 -11.806428)
		(size 0.7112)
		(drill 0.4064)
		(layers "F.Cu" "B.Cu")
		(net "GND")
	)
	(via
		(at 108.3818 -51.2318)
		(size 0.7112)
		(drill 0.4064)
		(layers "F.Cu" "B.Cu")
		(net "GND")
	)
	(via
		(at 120.751092 -91.042744)
		(size 0.7112)
		(drill 0.4064)
		(layers "F.Cu" "B.Cu")
		(net "GND")
	)
	(via
		(at 29.29382 -90.922856)
		(size 0.7112)
		(drill 0.4064)
		(layers "F.Cu" "B.Cu")
		(net "GND")
	)
	(via
		(at 135.539226 -11.806428)
		(size 0.7112)
		(drill 0.4064)
		(layers "F.Cu" "B.Cu")
		(net "GND")
	)
	(via
		(at 128.55829 -52.414678)
		(size 0.7112)
		(drill 0.4064)
		(layers "F.Cu" "B.Cu")
		(net "GND")
	)
	(via
		(at 70.06082 -112.385856)
		(size 0.7112)
		(drill 0.4064)
		(layers "F.Cu" "B.Cu")
		(net "GND")
	)
	(via
		(at 133.390894 -78.994)
		(size 0.7112)
		(drill 0.4064)
		(layers "F.Cu" "B.Cu")
		(net "GND")
	)
	(via
		(at 156.311092 -67.674744)
		(size 0.7112)
		(drill 0.4064)
		(layers "F.Cu" "B.Cu")
		(net "GND")
	)
	(via
		(at 91.414092 -118.220744)
		(size 0.7112)
		(drill 0.4064)
		(layers "F.Cu" "B.Cu")
		(net "GND")
	)
	(via
		(at 1.752092 -118.220744)
		(size 0.7112)
		(drill 0.4064)
		(layers "F.Cu" "B.Cu")
		(net "GND")
	)
	(via
		(at 71.094092 -118.220744)
		(size 0.7112)
		(drill 0.4064)
		(layers "F.Cu" "B.Cu")
		(net "GND")
	)
	(via
		(at 90.38082 -112.385856)
		(size 0.7112)
		(drill 0.4064)
		(layers "F.Cu" "B.Cu")
		(net "GND")
	)
	(via
		(at 14.097 -105.918)
		(size 0.7112)
		(drill 0.4064)
		(layers "F.Cu" "B.Cu")
		(net "GND")
	)
	(via
		(at 160.883092 -82.660744)
		(size 0.7112)
		(drill 0.4064)
		(layers "F.Cu" "B.Cu")
		(net "GND")
	)
	(via
		(at 136.163558 -52.372006)
		(size 0.7112)
		(drill 0.4064)
		(layers "F.Cu" "B.Cu")
		(net "GND")
	)
	(via
		(at 34.899092 -52.561744)
		(size 0.7112)
		(drill 0.4064)
		(layers "F.Cu" "B.Cu")
		(net "GND")
	)
	(via
		(at 9.339326 -62.721744)
		(size 0.7112)
		(drill 0.4064)
		(layers "F.Cu" "B.Cu")
		(net "GND")
	)
	(via
		(at 106.019092 -52.434744)
		(size 0.7112)
		(drill 0.4064)
		(layers "F.Cu" "B.Cu")
		(net "GND")
	)
	(via
		(at 137.388092 -58.022744)
		(size 0.7112)
		(drill 0.4064)
		(layers "F.Cu" "B.Cu")
		(net "GND")
	)
	(via
		(at 52.933092 -110.092744)
		(size 0.7112)
		(drill 0.3556)
		(layers "F.Cu" "B.Cu")
		(net "GND")
	)
	(via
		(at 149.225 -80.899)
		(size 0.7112)
		(drill 0.4064)
		(layers "F.Cu" "B.Cu")
		(net "GND")
	)
	(via
		(at 131.75869 -53.481478)
		(size 0.7112)
		(drill 0.4064)
		(layers "F.Cu" "B.Cu")
		(net "GND")
	)
	(via
		(at -1.803908 -83.109308)
		(size 0.7112)
		(drill 0.4064)
		(layers "F.Cu" "B.Cu")
		(net "GND")
	)
	(via
		(at 65.130426 -1.646428)
		(size 0.7112)
		(drill 0.4064)
		(layers "F.Cu" "B.Cu")
		(net "GND")
	)
	(via
		(at 133.578092 -8.492744)
		(size 0.7112)
		(drill 0.3556)
		(layers "F.Cu" "B.Cu")
		(net "GND")
	)
	(via
		(at 6.959092 -72.881744)
		(size 0.7112)
		(drill 0.4064)
		(layers "F.Cu" "B.Cu")
		(net "GND")
	)
	(via
		(at 59.77382 -96.002856)
		(size 0.7112)
		(drill 0.4064)
		(layers "F.Cu" "B.Cu")
		(net "GND")
	)
	(via
		(at 24.739092 -57.641744)
		(size 0.7112)
		(drill 0.4064)
		(layers "F.Cu" "B.Cu")
		(net "GND")
	)
	(via
		(at 66.014092 -118.220744)
		(size 0.7112)
		(drill 0.4064)
		(layers "F.Cu" "B.Cu")
		(net "GND")
	)
	(via
		(at 111.099092 -72.881744)
		(size 0.7112)
		(drill 0.4064)
		(layers "F.Cu" "B.Cu")
		(net "GND")
	)
	(via
		(at 6.959092 -70.341744)
		(size 0.7112)
		(drill 0.4064)
		(layers "F.Cu" "B.Cu")
		(net "GND")
	)
	(via
		(at -0.660908 -67.801744)
		(size 0.7112)
		(drill 0.4064)
		(layers "F.Cu" "B.Cu")
		(net "GND")
	)
	(via
		(at 60.934092 -118.220744)
		(size 0.7112)
		(drill 0.4064)
		(layers "F.Cu" "B.Cu")
		(net "GND")
	)
	(via
		(at 85.699092 -57.641744)
		(size 0.7112)
		(drill 0.4064)
		(layers "F.Cu" "B.Cu")
		(net "GND")
	)
	(via
		(at 44.53382 -106.162856)
		(size 0.7112)
		(drill 0.4064)
		(layers "F.Cu" "B.Cu")
		(net "GND")
	)
	(via
		(at 65.379092 -52.434744)
		(size 0.7112)
		(drill 0.4064)
		(layers "F.Cu" "B.Cu")
		(net "GND")
	)
	(via
		(at 156.438092 -62.086744)
		(size 0.7112)
		(drill 0.4064)
		(layers "F.Cu" "B.Cu")
		(net "GND")
	)
	(via
		(at 64.85382 -85.842856)
		(size 0.7112)
		(drill 0.4064)
		(layers "F.Cu" "B.Cu")
		(net "GND")
	)
	(via
		(at 154.178 -31.369)
		(size 0.7112)
		(drill 0.4064)
		(layers "F.Cu" "B.Cu")
		(net "GND")
	)
	(via
		(at 54.970426 -11.806428)
		(size 0.7112)
		(drill 0.4064)
		(layers "F.Cu" "B.Cu")
		(net "GND")
	)
	(via
		(at -0.660908 -65.261744)
		(size 0.7112)
		(drill 0.4064)
		(layers "F.Cu" "B.Cu")
		(net "GND")
	)
	(via
		(at 45.059092 -67.801744)
		(size 0.7112)
		(drill 0.4064)
		(layers "F.Cu" "B.Cu")
		(net "GND")
	)
	(via
		(at 39.979092 -67.801744)
		(size 0.7112)
		(drill 0.4064)
		(layers "F.Cu" "B.Cu")
		(net "GND")
	)
	(via
		(at 19.659092 -62.721744)
		(size 0.7112)
		(drill 0.4064)
		(layers "F.Cu" "B.Cu")
		(net "GND")
	)
	(via
		(at 105.49382 -106.162856)
		(size 0.7112)
		(drill 0.4064)
		(layers "F.Cu" "B.Cu")
		(net "GND")
	)
	(via
		(at 64.85382 -106.162856)
		(size 0.7112)
		(drill 0.4064)
		(layers "F.Cu" "B.Cu")
		(net "GND")
	)
	(segment
		(start 151.500078 -72.879966)
		(end 152.580086 -72.879966)
		(width 0.508)
		(layer "B.Cu")
		(net "GND")
	)
	(segment
		(start 148.960078 -72.879966)
		(end 150.040086 -72.879966)
		(width 0.508)
		(layer "B.Cu")
		(net "GND")
	)
	(segment
		(start 150.040086 -56.999886)
		(end 150.040086 -58.079894)
		(width 0.508)
		(layer "B.Cu")
		(net "GND")
	)
	(segment
		(start 150.040086 -62.079886)
		(end 151.120094 -62.079886)
		(width 0.508)
		(layer "B.Cu")
		(net "GND")
	)
	(segment
		(start 144.960086 -72.879966)
		(end 144.960086 -73.959974)
		(width 0.508)
		(layer "B.Cu")
		(net "GND")
	)
	(segment
		(start 150.040086 -67.799966)
		(end 151.120094 -67.799966)
		(width 0.508)
		(layer "B.Cu")
		(net "GND")
	)
	(segment
		(start 152.580086 -67.799966)
		(end 152.580086 -68.879974)
		(width 0.508)
		(layer "B.Cu")
		(net "GND")
	)
	(segment
		(start 150.040086 -69.259958)
		(end 150.040086 -70.339966)
		(width 0.508)
		(layer "B.Cu")
		(net "GND")
	)
	(segment
		(start -6.61797 -76.759308)
		(end -0.748792 -76.759308)
		(width 0.762)
		(layer "B.Cu")
		(net "GND")
	)
	(segment
		(start 143.880078 -65.259966)
		(end 144.960086 -65.259966)
		(width 0.508)
		(layer "B.Cu")
		(net "GND")
	)
	(segment
		(start 148.960078 -67.799966)
		(end 150.040086 -67.799966)
		(width 0.508)
		(layer "B.Cu")
		(net "GND")
	)
	(segment
		(start 147.500086 -72.879966)
		(end 147.500086 -73.959974)
		(width 0.508)
		(layer "B.Cu")
		(net "GND")
	)
	(segment
		(start 152.580086 -72.879966)
		(end 152.580086 -73.959974)
		(width 0.508)
		(layer "B.Cu")
		(net "GND")
	)
	(segment
		(start 147.500086 -71.799958)
		(end 147.500086 -72.879966)
		(width 0.508)
		(layer "B.Cu")
		(net "GND")
	)
	(segment
		(start 143.880078 -72.879966)
		(end 144.960086 -72.879966)
		(width 0.508)
		(layer "B.Cu")
		(net "GND")
	)
	(segment
		(start 144.960086 -70.339966)
		(end 144.960086 -71.419974)
		(width 0.508)
		(layer "B.Cu")
		(net "GND")
	)
	(segment
		(start 144.960086 -67.799966)
		(end 144.960086 -68.879974)
		(width 0.508)
		(layer "B.Cu")
		(net "GND")
	)
	(segment
		(start 152.580086 -58.459878)
		(end 152.580086 -59.539886)
		(width 0.508)
		(layer "B.Cu")
		(net "GND")
	)
	(segment
		(start -6.61797 -85.649308)
		(end -1.803908 -85.649308)
		(width 0.762)
		(layer "B.Cu")
		(net "GND")
	)
	(segment
		(start 146.420078 -67.799966)
		(end 147.500086 -67.799966)
		(width 0.508)
		(layer "B.Cu")
		(net "GND")
	)
	(segment
		(start 152.580086 -72.879966)
		(end 153.660094 -72.879966)
		(width 0.508)
		(layer "B.Cu")
		(net "GND")
	)
	(segment
		(start 152.580086 -64.179958)
		(end 152.580086 -65.259966)
		(width 0.508)
		(layer "B.Cu")
		(net "GND")
	)
	(segment
		(start 152.580086 -59.539886)
		(end 153.660094 -59.539886)
		(width 0.508)
		(layer "B.Cu")
		(net "GND")
	)
	(segment
		(start 144.960086 -66.719958)
		(end 144.960086 -67.799966)
		(width 0.508)
		(layer "B.Cu")
		(net "GND")
	)
	(segment
		(start 152.580086 -66.719958)
		(end 152.580086 -67.799966)
		(width 0.508)
		(layer "B.Cu")
		(net "GND")
	)
	(segment
		(start 153.36012 -111.131096)
		(end 153.36012 -112.300004)
		(width 0.508)
		(layer "B.Cu")
		(net "GND")
	)
	(segment
		(start 152.580086 -70.339966)
		(end 153.660094 -70.339966)
		(width 0.508)
		(layer "B.Cu")
		(net "GND")
	)
	(segment
		(start 147.500086 -67.799966)
		(end 147.500086 -68.879974)
		(width 0.508)
		(layer "B.Cu")
		(net "GND")
	)
	(segment
		(start 150.040086 -65.259966)
		(end 150.040086 -66.339974)
		(width 0.508)
		(layer "B.Cu")
		(net "GND")
	)
	(segment
		(start 150.040086 -72.879966)
		(end 150.040086 -73.959974)
		(width 0.508)
		(layer "B.Cu")
		(net "GND")
	)
	(segment
		(start 144.960086 -69.259958)
		(end 144.960086 -70.339966)
		(width 0.508)
		(layer "B.Cu")
		(net "GND")
	)
	(segment
		(start -6.61797 -88.189308)
		(end -1.676908 -88.189308)
		(width 0.762)
		(layer "B.Cu")
		(net "GND")
	)
	(segment
		(start 152.580086 -69.259958)
		(end 152.580086 -70.339966)
		(width 0.508)
		(layer "B.Cu")
		(net "GND")
	)
	(segment
		(start 150.040086 -67.799966)
		(end 150.040086 -68.879974)
		(width 0.508)
		(layer "B.Cu")
		(net "GND")
	)
	(segment
		(start 147.500086 -70.339966)
		(end 147.500086 -71.419974)
		(width 0.508)
		(layer "B.Cu")
		(net "GND")
	)
	(segment
		(start 152.580086 -71.799958)
		(end 152.580086 -72.879966)
		(width 0.508)
		(layer "B.Cu")
		(net "GND")
	)
	(segment
		(start 143.880078 -70.339966)
		(end 144.960086 -70.339966)
		(width 0.508)
		(layer "B.Cu")
		(net "GND")
	)
	(segment
		(start 151.500078 -65.259966)
		(end 152.580086 -65.259966)
		(width 0.508)
		(layer "B.Cu")
		(net "GND")
	)
	(segment
		(start 152.580086 -54.459886)
		(end 152.580086 -55.539894)
		(width 0.508)
		(layer "B.Cu")
		(net "GND")
	)
	(segment
		(start 147.500086 -64.179958)
		(end 147.500086 -65.259966)
		(width 0.508)
		(layer "B.Cu")
		(net "GND")
	)
	(segment
		(start 151.500078 -59.539886)
		(end 152.580086 -59.539886)
		(width 0.508)
		(layer "B.Cu")
		(net "GND")
	)
	(segment
		(start 150.040086 -65.259966)
		(end 151.120094 -65.259966)
		(width 0.508)
		(layer "B.Cu")
		(net "GND")
	)
	(segment
		(start 144.960086 -67.799966)
		(end 146.040094 -67.799966)
		(width 0.508)
		(layer "B.Cu")
		(net "GND")
	)
	(segment
		(start 144.960086 -65.259966)
		(end 144.960086 -66.339974)
		(width 0.508)
		(layer "B.Cu")
		(net "GND")
	)
	(segment
		(start 148.960078 -65.259966)
		(end 150.040086 -65.259966)
		(width 0.508)
		(layer "B.Cu")
		(net "GND")
	)
	(segment
		(start 144.960086 -71.799958)
		(end 144.960086 -72.879966)
		(width 0.508)
		(layer "B.Cu")
		(net "GND")
	)
	(segment
		(start 152.580086 -65.259966)
		(end 153.660094 -65.259966)
		(width 0.508)
		(layer "B.Cu")
		(net "GND")
	)
	(segment
		(start 143.880078 -67.799966)
		(end 144.960086 -67.799966)
		(width 0.508)
		(layer "B.Cu")
		(net "GND")
	)
	(segment
		(start 148.960078 -56.999886)
		(end 150.040086 -56.999886)
		(width 0.508)
		(layer "B.Cu")
		(net "GND")
	)
	(segment
		(start 152.580086 -65.259966)
		(end 152.580086 -66.339974)
		(width 0.508)
		(layer "B.Cu")
		(net "GND")
	)
	(segment
		(start 150.040086 -72.879966)
		(end 151.120094 -72.879966)
		(width 0.508)
		(layer "B.Cu")
		(net "GND")
	)
	(segment
		(start 148.960078 -62.079886)
		(end 150.040086 -62.079886)
		(width 0.508)
		(layer "B.Cu")
		(net "GND")
	)
	(segment
		(start 153.36012 -112.300004)
		(end 154.529028 -112.300004)
		(width 0.508)
		(layer "B.Cu")
		(net "GND")
	)
	(segment
		(start 150.040086 -56.999886)
		(end 151.120094 -56.999886)
		(width 0.508)
		(layer "B.Cu")
		(net "GND")
	)
	(segment
		(start 151.500078 -70.339966)
		(end 152.580086 -70.339966)
		(width 0.508)
		(layer "B.Cu")
		(net "GND")
	)
	(segment
		(start 150.040086 -62.079886)
		(end 150.040086 -63.159894)
		(width 0.508)
		(layer "B.Cu")
		(net "GND")
	)
	(segment
		(start 147.500086 -67.799966)
		(end 148.580094 -67.799966)
		(width 0.508)
		(layer "B.Cu")
		(net "GND")
	)
	(segment
		(start 147.500086 -70.339966)
		(end 148.580094 -70.339966)
		(width 0.508)
		(layer "B.Cu")
		(net "GND")
	)
	(segment
		(start 146.420078 -72.879966)
		(end 147.500086 -72.879966)
		(width 0.508)
		(layer "B.Cu")
		(net "GND")
	)
	(segment
		(start 146.420078 -65.259966)
		(end 147.500086 -65.259966)
		(width 0.508)
		(layer "B.Cu")
		(net "GND")
	)
	(segment
		(start 152.191212 -112.300004)
		(end 153.36012 -112.300004)
		(width 0.508)
		(layer "B.Cu")
		(net "GND")
	)
	(segment
		(start 147.500086 -65.259966)
		(end 148.580094 -65.259966)
		(width 0.508)
		(layer "B.Cu")
		(net "GND")
	)
	(segment
		(start 144.960086 -70.339966)
		(end 146.040094 -70.339966)
		(width 0.508)
		(layer "B.Cu")
		(net "GND")
	)
	(segment
		(start -1.676908 -90.729308)
		(end -6.61797 -90.729308)
		(width 0.762)
		(layer "B.Cu")
		(net "GND")
	)
	(segment
		(start 150.040086 -70.339966)
		(end 150.040086 -71.419974)
		(width 0.508)
		(layer "B.Cu")
		(net "GND")
	)
	(segment
		(start 147.500086 -72.879966)
		(end 148.580094 -72.879966)
		(width 0.508)
		(layer "B.Cu")
		(net "GND")
	)
	(segment
		(start 152.580086 -67.799966)
		(end 153.660094 -67.799966)
		(width 0.508)
		(layer "B.Cu")
		(net "GND")
	)
	(segment
		(start 150.040086 -66.719958)
		(end 150.040086 -67.799966)
		(width 0.508)
		(layer "B.Cu")
		(net "GND")
	)
	(segment
		(start 152.580086 -54.459886)
		(end 153.660094 -54.459886)
		(width 0.508)
		(layer "B.Cu")
		(net "GND")
	)
	(segment
		(start 147.500086 -66.719958)
		(end 147.500086 -67.799966)
		(width 0.508)
		(layer "B.Cu")
		(net "GND")
	)
	(segment
		(start 153.36012 -112.300004)
		(end 153.36012 -113.468912)
		(width 0.508)
		(layer "B.Cu")
		(net "GND")
	)
	(segment
		(start 150.040086 -71.799958)
		(end 150.040086 -72.879966)
		(width 0.508)
		(layer "B.Cu")
		(net "GND")
	)
	(segment
		(start 142.110206 -108.599986)
		(end 143.279114 -108.599986)
		(width 0.508)
		(layer "B.Cu")
		(net "GND")
	)
	(segment
		(start 144.960086 -65.259966)
		(end 146.040094 -65.259966)
		(width 0.508)
		(layer "B.Cu")
		(net "GND")
	)
	(segment
		(start 150.040086 -70.339966)
		(end 151.120094 -70.339966)
		(width 0.508)
		(layer "B.Cu")
		(net "GND")
	)
	(segment
		(start 150.040086 -60.999878)
		(end 150.040086 -62.079886)
		(width 0.508)
		(layer "B.Cu")
		(net "GND")
	)
	(segment
		(start 146.420078 -70.339966)
		(end 147.500086 -70.339966)
		(width 0.508)
		(layer "B.Cu")
		(net "GND")
	)
	(segment
		(start 144.960086 -72.879966)
		(end 146.040094 -72.879966)
		(width 0.508)
		(layer "B.Cu")
		(net "GND")
	)
	(segment
		(start 142.110206 -108.599986)
		(end 142.110206 -109.768894)
		(width 0.508)
		(layer "B.Cu")
		(net "GND")
	)
	(segment
		(start 150.040086 -55.919878)
		(end 150.040086 -56.999886)
		(width 0.508)
		(layer "B.Cu")
		(net "GND")
	)
	(segment
		(start 152.580086 -70.339966)
		(end 152.580086 -71.419974)
		(width 0.508)
		(layer "B.Cu")
		(net "GND")
	)
	(segment
		(start 148.960078 -70.339966)
		(end 150.040086 -70.339966)
		(width 0.508)
		(layer "B.Cu")
		(net "GND")
	)
	(segment
		(start 150.040086 -64.179958)
		(end 150.040086 -65.259966)
		(width 0.508)
		(layer "B.Cu")
		(net "GND")
	)
	(segment
		(start 151.500078 -54.459886)
		(end 152.580086 -54.459886)
		(width 0.508)
		(layer "B.Cu")
		(net "GND")
	)
	(segment
		(start 152.580086 -59.539886)
		(end 152.580086 -60.619894)
		(width 0.508)
		(layer "B.Cu")
		(net "GND")
	)
	(segment
		(start 140.941298 -108.599986)
		(end 142.110206 -108.599986)
		(width 0.508)
		(layer "B.Cu")
		(net "GND")
	)
	(segment
		(start 151.500078 -67.799966)
		(end 152.580086 -67.799966)
		(width 0.508)
		(layer "B.Cu")
		(net "GND")
	)
	(segment
		(start 144.960086 -64.179958)
		(end 144.960086 -65.259966)
		(width 0.508)
		(layer "B.Cu")
		(net "GND")
	)
	(segment
		(start 147.500086 -65.259966)
		(end 147.500086 -66.339974)
		(width 0.508)
		(layer "B.Cu")
		(net "GND")
	)
	(segment
		(start 147.500086 -69.259958)
		(end 147.500086 -70.339966)
		(width 0.508)
		(layer "B.Cu")
		(net "GND")
	)
	(segment
		(start 17.677638 -94.990666)
		(end 17.98066 -94.687644)
		(width 0.1397)
		(layer "F.Cu")
		(net "I2C_C_BUF_SDA")
	)
	(segment
		(start 23.61692 -94.687644)
		(end 20.574 -94.687644)
		(width 0.1397)
		(layer "F.Cu")
		(net "I2C_C_BUF_SDA")
	)
	(segment
		(start 35.26282 -83.041744)
		(end 23.61692 -94.687644)
		(width 0.1397)
		(layer "F.Cu")
		(net "I2C_C_BUF_SDA")
	)
	(segment
		(start 135.285734 -67.896486)
		(end 135.077962 -67.896486)
		(width 0.1397)
		(layer "F.Cu")
		(net "I2C_C_BUF_SDA")
	)
	(segment
		(start 119.932704 -83.041744)
		(end 35.26282 -83.041744)
		(width 0.1397)
		(layer "F.Cu")
		(net "I2C_C_BUF_SDA")
	)
	(segment
		(start 17.6784 -96.071944)
		(end 17.677638 -96.071182)
		(width 0.1397)
		(layer "F.Cu")
		(net "I2C_C_BUF_SDA")
	)
	(segment
		(start 135.077962 -67.896486)
		(end 119.932704 -83.041744)
		(width 0.1397)
		(layer "F.Cu")
		(net "I2C_C_BUF_SDA")
	)
	(segment
		(start 17.98066 -94.687644)
		(end 20.574 -94.687644)
		(width 0.1397)
		(layer "F.Cu")
		(net "I2C_C_BUF_SDA")
	)
	(segment
		(start 135.707882 -68.318634)
		(end 135.285734 -67.896486)
		(width 0.1397)
		(layer "F.Cu")
		(net "I2C_C_BUF_SDA")
	)
	(segment
		(start 17.677638 -96.071182)
		(end 17.677638 -94.990666)
		(width 0.1397)
		(layer "F.Cu")
		(net "I2C_C_BUF_SDA")
	)
	(via
		(at 20.574 -94.687644)
		(size 0.7112)
		(drill 0.3556)
		(layers "F.Cu" "B.Cu")
		(net "I2C_C_BUF_SDA")
	)
	(segment
		(start -3.20294 -76.759308)
		(end -6.99897 -76.759308)
		(width 0.762)
		(layer "F.Cu")
		(net "P5VA")
	)
	(segment
		(start -2.154174 -76.759308)
		(end -3.20294 -76.759308)
		(width 1.016)
		(layer "F.Cu")
		(net "P5VA")
	)
	(segment
		(start 0.592836 -79.506318)
		(end -2.154174 -76.759308)
		(width 1.016)
		(layer "F.Cu")
		(net "P5VA")
	)
	(segment
		(start 0.592836 -80.938116)
		(end 0.592836 -79.506318)
		(width 1.016)
		(layer "F.Cu")
		(net "P5VA")
	)
	(segment
		(start 156.920692 -103.869744)
		(end 156.920692 -104.902)
		(width 0.762)
		(layer "F.Cu")
		(net "P5VA")
	)
	(via
		(at 156.920692 -104.902)
		(size 0.7112)
		(drill 0.4064)
		(layers "F.Cu" "B.Cu")
		(net "P5VA")
	)
	(via
		(at 5.308092 -82.660744)
		(size 0.7112)
		(drill 0.3556)
		(layers "F.Cu" "B.Cu")
		(net "P5VA")
	)
	(via
		(at 0.592836 -80.938116)
		(size 0.7112)
		(drill 0.4064)
		(layers "F.Cu" "B.Cu")
		(net "P5VA")
	)
	(via
		(at 136.245092 -106.409744)
		(size 0.7112)
		(drill 0.3556)
		(layers "F.Cu" "B.Cu")
		(net "P5VA")
	)
	(segment
		(start 10.515092 -85.200744)
		(end 7.975092 -82.660744)
		(width 1.016)
		(layer "B.Cu")
		(net "P5VA")
	)
	(segment
		(start 132.816092 -106.409744)
		(end 129.133092 -102.726744)
		(width 1.016)
		(layer "B.Cu")
		(net "P5VA")
	)
	(segment
		(start 8.128 -98.685604)
		(end 8.128 -97.028)
		(width 1.016)
		(layer "B.Cu")
		(net "P5VA")
	)
	(segment
		(start 0.592836 -80.938116)
		(end 2.315464 -82.660744)
		(width 1.016)
		(layer "B.Cu")
		(net "P5VA")
	)
	(segment
		(start 13.073888 -102.726236)
		(end 9.965944 -99.618292)
		(width 1.016)
		(layer "B.Cu")
		(net "P5VA")
	)
	(segment
		(start 156.920692 -105.413048)
		(end 155.923996 -106.409744)
		(width 1.016)
		(layer "B.Cu")
		(net "P5VA")
	)
	(segment
		(start 2.315464 -82.660744)
		(end 5.308092 -82.660744)
		(width 1.016)
		(layer "B.Cu")
		(net "P5VA")
	)
	(segment
		(start 156.920692 -104.902)
		(end 156.920692 -105.413048)
		(width 1.016)
		(layer "B.Cu")
		(net "P5VA")
	)
	(segment
		(start 9.061704 -99.618292)
		(end 9.011412 -99.568)
		(width 1.016)
		(layer "B.Cu")
		(net "P5VA")
	)
	(segment
		(start 136.245092 -106.409744)
		(end 132.816092 -106.409744)
		(width 1.016)
		(layer "B.Cu")
		(net "P5VA")
	)
	(segment
		(start 155.923996 -106.409744)
		(end 136.245092 -106.409744)
		(width 1.016)
		(layer "B.Cu")
		(net "P5VA")
	)
	(segment
		(start 9.965944 -99.618292)
		(end 9.061704 -99.618292)
		(width 1.016)
		(layer "B.Cu")
		(net "P5VA")
	)
	(segment
		(start 10.515092 -94.640908)
		(end 10.515092 -85.200744)
		(width 1.016)
		(layer "B.Cu")
		(net "P5VA")
	)
	(segment
		(start 7.975092 -82.660744)
		(end 5.308092 -82.660744)
		(width 1.016)
		(layer "B.Cu")
		(net "P5VA")
	)
	(segment
		(start 9.011412 -99.568)
		(end 9.010396 -99.568)
		(width 1.016)
		(layer "B.Cu")
		(net "P5VA")
	)
	(segment
		(start 129.133092 -102.726744)
		(end 13.074904 -102.726744)
		(width 1.016)
		(layer "B.Cu")
		(net "P5VA")
	)
	(segment
		(start 13.074904 -102.726744)
		(end 13.073888 -102.726236)
		(width 1.016)
		(layer "B.Cu")
		(net "P5VA")
	)
	(segment
		(start 9.010396 -99.568)
		(end 8.128 -98.685604)
		(width 1.016)
		(layer "B.Cu")
		(net "P5VA")
	)
	(segment
		(start 8.128 -97.028)
		(end 10.515092 -94.640908)
		(width 1.016)
		(layer "B.Cu")
		(net "P5VA")
	)
	(segment
		(start 135.353044 -76.392278)
		(end 137.346944 -78.386178)
		(width 0.1397)
		(layer "F.Cu")
		(net "TRAY_MOSFET_G")
	)
	(segment
		(start 134.640574 -76.392278)
		(end 135.353044 -76.392278)
		(width 0.1397)
		(layer "F.Cu")
		(net "TRAY_MOSFET_G")
	)
	(segment
		(start 132.588 -81.5975)
		(end 132.588 -78.444852)
		(width 0.1397)
		(layer "F.Cu")
		(net "TRAY_MOSFET_G")
	)
	(segment
		(start 132.588 -78.444852)
		(end 134.640574 -76.392278)
		(width 0.1397)
		(layer "F.Cu")
		(net "TRAY_MOSFET_G")
	)
	(segment
		(start 137.346944 -83.363308)
		(end 137.346944 -78.715108)
		(width 0.1397)
		(layer "F.Cu")
		(net "TRAY_MOSFET_G")
	)
	(segment
		(start 137.346944 -78.386178)
		(end 137.346944 -78.715108)
		(width 0.1397)
		(layer "F.Cu")
		(net "TRAY_MOSFET_G")
	)
	(segment
		(start 136.737344 -83.972908)
		(end 137.346944 -83.363308)
		(width 0.1397)
		(layer "F.Cu")
		(net "TRAY_MOSFET_G")
	)
	(segment
		(start 135.530844 -83.972908)
		(end 136.737344 -83.972908)
		(width 0.1397)
		(layer "F.Cu")
		(net "TRAY_MOSFET_G")
	)
	(segment
		(start 132.7785 -81.788)
		(end 132.588 -81.5975)
		(width 0.1397)
		(layer "F.Cu")
		(net "TRAY_MOSFET_G")
	)
	(via
		(at 137.346944 -78.715108)
		(size 0.7112)
		(drill 0.3556)
		(layers "F.Cu" "B.Cu")
		(net "TRAY_MOSFET_G")
	)
	(segment
		(start 17.665446 -93.845634)
		(end 18.999962 -93.845634)
		(width 0.1397)
		(layer "F.Cu")
		(net "I2C_C_BUF_SCL")
	)
	(segment
		(start 135.38073 -67.375786)
		(end 134.862062 -67.375786)
		(width 0.1397)
		(layer "F.Cu")
		(net "I2C_C_BUF_SCL")
	)
	(segment
		(start 134.862062 -67.375786)
		(end 119.716804 -82.521044)
		(width 0.1397)
		(layer "F.Cu")
		(net "I2C_C_BUF_SCL")
	)
	(segment
		(start 23.72233 -93.845634)
		(end 18.999962 -93.845634)
		(width 0.1397)
		(layer "F.Cu")
		(net "I2C_C_BUF_SCL")
	)
	(segment
		(start 17.665192 -93.84538)
		(end 17.665446 -93.845634)
		(width 0.1397)
		(layer "F.Cu")
		(net "I2C_C_BUF_SCL")
	)
	(segment
		(start 135.707882 -67.048634)
		(end 135.38073 -67.375786)
		(width 0.1397)
		(layer "F.Cu")
		(net "I2C_C_BUF_SCL")
	)
	(segment
		(start 17.665192 -92.75318)
		(end 17.665192 -93.84538)
		(width 0.1397)
		(layer "F.Cu")
		(net "I2C_C_BUF_SCL")
	)
	(segment
		(start 119.716804 -82.521044)
		(end 35.04692 -82.521044)
		(width 0.1397)
		(layer "F.Cu")
		(net "I2C_C_BUF_SCL")
	)
	(segment
		(start 17.663414 -92.751402)
		(end 17.665192 -92.75318)
		(width 0.1397)
		(layer "F.Cu")
		(net "I2C_C_BUF_SCL")
	)
	(segment
		(start 35.04692 -82.521044)
		(end 23.72233 -93.845634)
		(width 0.1397)
		(layer "F.Cu")
		(net "I2C_C_BUF_SCL")
	)
	(via
		(at 18.999962 -93.845634)
		(size 0.7112)
		(drill 0.3556)
		(layers "F.Cu" "B.Cu")
		(net "I2C_C_BUF_SCL")
	)
	(segment
		(start 139.1793 -109.0422)
		(end 138.715496 -109.0422)
		(width 0.1397)
		(layer "F.Cu")
		(net "TPS2490_EN2")
	)
	(segment
		(start 137.6045 -109.0295)
		(end 124.723906 -96.148906)
		(width 0.1397)
		(layer "F.Cu")
		(net "TPS2490_EN2")
	)
	(segment
		(start 141.7955 -111.0615)
		(end 139.7762 -109.0422)
		(width 0.1397)
		(layer "F.Cu")
		(net "TPS2490_EN2")
	)
	(segment
		(start 139.192 -109.0295)
		(end 139.1793 -109.0422)
		(width 0.1397)
		(layer "F.Cu")
		(net "TPS2490_EN2")
	)
	(segment
		(start 147.660106 -110.000034)
		(end 146.59864 -111.0615)
		(width 0.1397)
		(layer "F.Cu")
		(net "TPS2490_EN2")
	)
	(segment
		(start 138.715496 -109.0422)
		(end 138.702796 -109.0295)
		(width 0.1397)
		(layer "F.Cu")
		(net "TPS2490_EN2")
	)
	(segment
		(start 124.723906 -95.767906)
		(end 124.333 -95.377)
		(width 0.1397)
		(layer "F.Cu")
		(net "TPS2490_EN2")
	)
	(segment
		(start 146.59864 -111.0615)
		(end 141.7955 -111.0615)
		(width 0.1397)
		(layer "F.Cu")
		(net "TPS2490_EN2")
	)
	(segment
		(start 139.2047 -109.0422)
		(end 139.192 -109.0295)
		(width 0.1397)
		(layer "F.Cu")
		(net "TPS2490_EN2")
	)
	(segment
		(start 139.7762 -109.0422)
		(end 139.2047 -109.0422)
		(width 0.1397)
		(layer "F.Cu")
		(net "TPS2490_EN2")
	)
	(segment
		(start 138.702796 -109.0295)
		(end 137.6045 -109.0295)
		(width 0.1397)
		(layer "F.Cu")
		(net "TPS2490_EN2")
	)
	(segment
		(start 124.723906 -96.148906)
		(end 124.723906 -95.767906)
		(width 0.1397)
		(layer "F.Cu")
		(net "TPS2490_EN2")
	)
	(via
		(at 124.333 -95.377)
		(size 0.7112)
		(drill 0.4064)
		(layers "F.Cu" "B.Cu")
		(net "TPS2490_EN2")
	)
	(via
		(at 155.637738 -23.627842)
		(size 0.7112)
		(drill 0.3556)
		(layers "F.Cu" "B.Cu")
		(net "TPS2490_EN2")
	)
	(segment
		(start 140.153136 -56.321706)
		(end 143.062706 -53.412136)
		(width 0.1397)
		(layer "B.Cu")
		(net "TPS2490_EN2")
	)
	(segment
		(start 155.6385 -23.628604)
		(end 155.637738 -23.627842)
		(width 0.1397)
		(layer "B.Cu")
		(net "TPS2490_EN2")
	)
	(segment
		(start 124.333 -95.377)
		(end 124.333 -86.425278)
		(width 0.1397)
		(layer "B.Cu")
		(net "TPS2490_EN2")
	)
	(segment
		(start 155.6385 -52.1335)
		(end 155.6385 -23.628604)
		(width 0.1397)
		(layer "B.Cu")
		(net "TPS2490_EN2")
	)
	(segment
		(start 146.452336 -53.412136)
		(end 147.500086 -54.459886)
		(width 0.1397)
		(layer "B.Cu")
		(net "TPS2490_EN2")
	)
	(segment
		(start 147.500086 -54.459886)
		(end 148.492972 -53.467)
		(width 0.1397)
		(layer "B.Cu")
		(net "TPS2490_EN2")
	)
	(segment
		(start 143.062706 -53.412136)
		(end 146.452336 -53.412136)
		(width 0.1397)
		(layer "B.Cu")
		(net "TPS2490_EN2")
	)
	(segment
		(start 152.910032 -18.999962)
		(end 152.910032 -20.69973)
		(width 0.1397)
		(layer "B.Cu")
		(net "TPS2490_EN2")
	)
	(segment
		(start 148.492972 -53.467)
		(end 154.305 -53.467)
		(width 0.1397)
		(layer "B.Cu")
		(net "TPS2490_EN2")
	)
	(segment
		(start 152.910032 -20.69973)
		(end 155.637738 -23.427436)
		(width 0.1397)
		(layer "B.Cu")
		(net "TPS2490_EN2")
	)
	(segment
		(start 155.637738 -23.427436)
		(end 155.637738 -23.627842)
		(width 0.1397)
		(layer "B.Cu")
		(net "TPS2490_EN2")
	)
	(segment
		(start 140.153136 -70.605142)
		(end 140.153136 -56.321706)
		(width 0.1397)
		(layer "B.Cu")
		(net "TPS2490_EN2")
	)
	(segment
		(start 154.305 -53.467)
		(end 155.6385 -52.1335)
		(width 0.1397)
		(layer "B.Cu")
		(net "TPS2490_EN2")
	)
	(segment
		(start 124.333 -86.425278)
		(end 140.153136 -70.605142)
		(width 0.1397)
		(layer "B.Cu")
		(net "TPS2490_EN2")
	)
	(segment
		(start 149.302724 -110.000034)
		(end 147.796758 -111.506)
		(width 0.1397)
		(layer "F.Cu")
		(net "TPS2490_EN1")
	)
	(segment
		(start 141.605 -111.506)
		(end 140.0175 -109.9185)
		(width 0.1397)
		(layer "F.Cu")
		(net "TPS2490_EN1")
	)
	(segment
		(start 139.192 -109.9185)
		(end 139.1793 -109.9058)
		(width 0.1397)
		(layer "F.Cu")
		(net "TPS2490_EN1")
	)
	(segment
		(start 139.668504 -109.9058)
		(end 139.2047 -109.9058)
		(width 0.1397)
		(layer "F.Cu")
		(net "TPS2490_EN1")
	)
	(segment
		(start 139.2047 -109.9058)
		(end 139.192 -109.9185)
		(width 0.1397)
		(layer "F.Cu")
		(net "TPS2490_EN1")
	)
	(segment
		(start 138.715496 -109.9058)
		(end 138.702796 -109.9185)
		(width 0.1397)
		(layer "F.Cu")
		(net "TPS2490_EN1")
	)
	(segment
		(start 150.160228 -110.000034)
		(end 149.302724 -110.000034)
		(width 0.1397)
		(layer "F.Cu")
		(net "TPS2490_EN1")
	)
	(segment
		(start 137.8585 -109.9185)
		(end 123.317 -95.377)
		(width 0.1397)
		(layer "F.Cu")
		(net "TPS2490_EN1")
	)
	(segment
		(start 138.702796 -109.9185)
		(end 137.8585 -109.9185)
		(width 0.1397)
		(layer "F.Cu")
		(net "TPS2490_EN1")
	)
	(segment
		(start 140.0175 -109.9185)
		(end 139.681204 -109.9185)
		(width 0.1397)
		(layer "F.Cu")
		(net "TPS2490_EN1")
	)
	(segment
		(start 139.1793 -109.9058)
		(end 138.715496 -109.9058)
		(width 0.1397)
		(layer "F.Cu")
		(net "TPS2490_EN1")
	)
	(segment
		(start 147.796758 -111.506)
		(end 141.605 -111.506)
		(width 0.1397)
		(layer "F.Cu")
		(net "TPS2490_EN1")
	)
	(segment
		(start 139.681204 -109.9185)
		(end 139.668504 -109.9058)
		(width 0.1397)
		(layer "F.Cu")
		(net "TPS2490_EN1")
	)
	(via
		(at 123.317 -95.377)
		(size 0.7112)
		(drill 0.4064)
		(layers "F.Cu" "B.Cu")
		(net "TPS2490_EN1")
	)
	(via
		(at 154.94 -25.4)
		(size 0.7112)
		(drill 0.3556)
		(layers "F.Cu" "B.Cu")
		(net "TPS2490_EN1")
	)
	(segment
		(start 155.194 -25.654)
		(end 154.94 -25.4)
		(width 0.1397)
		(layer "B.Cu")
		(net "TPS2490_EN1")
	)
	(segment
		(start 123.317 -95.377)
		(end 123.879864 -94.814136)
		(width 0.1397)
		(layer "B.Cu")
		(net "TPS2490_EN1")
	)
	(segment
		(start 142.875 -52.959)
		(end 146.460972 -52.959)
		(width 0.1397)
		(layer "B.Cu")
		(net "TPS2490_EN1")
	)
	(segment
		(start 153.924 -52.959)
		(end 155.194 -51.689)
		(width 0.1397)
		(layer "B.Cu")
		(net "TPS2490_EN1")
	)
	(segment
		(start 155.194 -51.689)
		(end 155.194 -25.654)
		(width 0.1397)
		(layer "B.Cu")
		(net "TPS2490_EN1")
	)
	(segment
		(start 139.7 -70.429628)
		(end 139.7 -56.134)
		(width 0.1397)
		(layer "B.Cu")
		(net "TPS2490_EN1")
	)
	(segment
		(start 139.7 -56.134)
		(end 142.875 -52.959)
		(width 0.1397)
		(layer "B.Cu")
		(net "TPS2490_EN1")
	)
	(segment
		(start 123.879864 -86.249764)
		(end 139.7 -70.429628)
		(width 0.1397)
		(layer "B.Cu")
		(net "TPS2490_EN1")
	)
	(segment
		(start 123.879864 -94.814136)
		(end 123.879864 -86.249764)
		(width 0.1397)
		(layer "B.Cu")
		(net "TPS2490_EN1")
	)
	(segment
		(start 151.409908 -20.999958)
		(end 152.190958 -20.999958)
		(width 0.1397)
		(layer "B.Cu")
		(net "TPS2490_EN1")
	)
	(segment
		(start 152.190958 -20.999958)
		(end 154.94 -23.749)
		(width 0.1397)
		(layer "B.Cu")
		(net "TPS2490_EN1")
	)
	(segment
		(start 148.5392 -52.959)
		(end 153.924 -52.959)
		(width 0.1397)
		(layer "B.Cu")
		(net "TPS2490_EN1")
	)
	(segment
		(start 154.94 -23.749)
		(end 154.94 -25.4)
		(width 0.1397)
		(layer "B.Cu")
		(net "TPS2490_EN1")
	)
	(segment
		(start 147.500086 -51.919886)
		(end 148.5392 -52.959)
		(width 0.1397)
		(layer "B.Cu")
		(net "TPS2490_EN1")
	)
	(segment
		(start 146.460972 -52.959)
		(end 147.500086 -51.919886)
		(width 0.1397)
		(layer "B.Cu")
		(net "TPS2490_EN1")
	)
	(segment
		(start 15.253208 -98.359468)
		(end 14.625828 -97.732088)
		(width 0.1397)
		(layer "F.Cu")
		(net "I2C_C_BUF_READY")
	)
	(segment
		(start 17.121632 -99.379786)
		(end 16.101314 -98.359468)
		(width 0.1397)
		(layer "F.Cu")
		(net "I2C_C_BUF_READY")
	)
	(segment
		(start 16.101314 -98.359468)
		(end 15.253208 -98.359468)
		(width 0.1397)
		(layer "F.Cu")
		(net "I2C_C_BUF_READY")
	)
	(segment
		(start 14.625828 -97.732088)
		(end 14.625828 -96.431608)
		(width 0.1397)
		(layer "F.Cu")
		(net "I2C_C_BUF_READY")
	)
	(segment
		(start 12.27455 -90.3986)
		(end 11.496802 -90.3986)
		(width 0.1397)
		(layer "F.Cu")
		(net "I2C_C_BUF_EN")
	)
	(segment
		(start 11.496802 -90.3986)
		(end 10.931652 -89.83345)
		(width 0.1397)
		(layer "F.Cu")
		(net "I2C_C_BUF_EN")
	)
	(segment
		(start 12.675108 -92.291408)
		(end 12.675108 -90.799158)
		(width 0.1397)
		(layer "F.Cu")
		(net "I2C_C_BUF_EN")
	)
	(segment
		(start 12.675108 -90.799158)
		(end 12.27455 -90.3986)
		(width 0.1397)
		(layer "F.Cu")
		(net "I2C_C_BUF_EN")
	)
	(via
		(at 10.931652 -89.83345)
		(size 0.7112)
		(drill 0.3556)
		(layers "F.Cu" "B.Cu")
		(net "I2C_C_BUF_EN")
	)
	(via
		(at 134.366 -89.789)
		(size 0.7112)
		(drill 0.3556)
		(layers "F.Cu" "B.Cu")
		(net "IR_SWITCH_E")
	)
	(segment
		(start 134.667244 -83.386422)
		(end 134.641844 -83.411822)
		(width 0.1397)
		(layer "F.Cu")
		(net "TRAY PRESENT_OUT_NET")
	)
	(segment
		(start 134.641844 -85.065108)
		(end 133.807962 -85.89899)
		(width 0.1397)
		(layer "F.Cu")
		(net "TRAY PRESENT_OUT_NET")
	)
	(segment
		(start 134.641844 -83.411822)
		(end 134.641844 -83.972908)
		(width 0.1397)
		(layer "F.Cu")
		(net "TRAY PRESENT_OUT_NET")
	)
	(segment
		(start 134.667244 -81.813908)
		(end 134.667244 -82.906108)
		(width 0.1397)
		(layer "F.Cu")
		(net "TRAY PRESENT_OUT_NET")
	)
	(segment
		(start 134.667244 -82.906108)
		(end 134.667244 -83.386422)
		(width 0.1397)
		(layer "F.Cu")
		(net "TRAY PRESENT_OUT_NET")
	)
	(segment
		(start 133.807962 -85.89899)
		(end 133.67258 -85.89899)
		(width 0.1397)
		(layer "F.Cu")
		(net "TRAY PRESENT_OUT_NET")
	)
	(segment
		(start 134.641844 -83.972908)
		(end 134.641844 -85.065108)
		(width 0.1397)
		(layer "F.Cu")
		(net "TRAY PRESENT_OUT_NET")
	)
	(via
		(at 133.67258 -85.89899)
		(size 0.7112)
		(drill 0.3556)
		(layers "F.Cu" "B.Cu")
		(net "TRAY PRESENT_OUT_NET")
	)
	(segment
		(start 23.558246 -82.787998)
		(end 25.767792 -82.787998)
		(width 0.1397)
		(layer "F.Cu")
		(net "SELF_TRAY_PRESENT")
	)
	(segment
		(start 25.767792 -82.787998)
		(end 26.288746 -82.267044)
		(width 0.1397)
		(layer "F.Cu")
		(net "SELF_TRAY_PRESENT")
	)
	(segment
		(start 145.692114 -62.079886)
		(end 144.960086 -62.079886)
		(width 0.1397)
		(layer "F.Cu")
		(net "SELF_TRAY_PRESENT")
	)
	(segment
		(start 146.685 -50.927)
		(end 146.177 -51.435)
		(width 0.1397)
		(layer "F.Cu")
		(net "SELF_TRAY_PRESENT")
	)
	(segment
		(start 155.2321 -51.816)
		(end 154.3431 -50.927)
		(width 0.1397)
		(layer "F.Cu")
		(net "SELF_TRAY_PRESENT")
	)
	(segment
		(start 148.717 -60.198)
		(end 148.209 -60.706)
		(width 0.1397)
		(layer "F.Cu")
		(net "SELF_TRAY_PRESENT")
	)
	(segment
		(start 2.54 -84.328)
		(end 4.080256 -82.787744)
		(width 0.1397)
		(layer "F.Cu")
		(net "SELF_TRAY_PRESENT")
	)
	(segment
		(start 26.288746 -82.267044)
		(end 26.288746 -82.26679)
		(width 0.1397)
		(layer "F.Cu")
		(net "SELF_TRAY_PRESENT")
	)
	(segment
		(start 153.858722 -74.487278)
		(end 155.2321 -73.1139)
		(width 0.1397)
		(layer "F.Cu")
		(net "SELF_TRAY_PRESENT")
	)
	(segment
		(start 142.851886 -62.079886)
		(end 142.364714 -61.592714)
		(width 0.1397)
		(layer "F.Cu")
		(net "SELF_TRAY_PRESENT")
	)
	(segment
		(start 29.07411 -79.481426)
		(end 90.955622 -79.481426)
		(width 0.1397)
		(layer "F.Cu")
		(net "SELF_TRAY_PRESENT")
	)
	(segment
		(start 148.336 -58.547)
		(end 148.717 -58.928)
		(width 0.1397)
		(layer "F.Cu")
		(net "SELF_TRAY_PRESENT")
	)
	(segment
		(start 146.177 -51.435)
		(end 146.177 -54.864)
		(width 0.1397)
		(layer "F.Cu")
		(net "SELF_TRAY_PRESENT")
	)
	(segment
		(start 142.364714 -61.592714)
		(end 136.982454 -61.592714)
		(width 0.1397)
		(layer "F.Cu")
		(net "SELF_TRAY_PRESENT")
	)
	(segment
		(start 134.368794 -74.487278)
		(end 136.650222 -74.487278)
		(width 0.1397)
		(layer "F.Cu")
		(net "SELF_TRAY_PRESENT")
	)
	(segment
		(start 119.093742 -79.481426)
		(end 90.955622 -79.481426)
		(width 0.1397)
		(layer "F.Cu")
		(net "SELF_TRAY_PRESENT")
	)
	(segment
		(start 148.717 -58.928)
		(end 148.717 -60.198)
		(width 0.1397)
		(layer "F.Cu")
		(net "SELF_TRAY_PRESENT")
	)
	(segment
		(start 136.650222 -74.487278)
		(end 153.858722 -74.487278)
		(width 0.1397)
		(layer "F.Cu")
		(net "SELF_TRAY_PRESENT")
	)
	(segment
		(start 136.982454 -61.592714)
		(end 119.093742 -79.481426)
		(width 0.1397)
		(layer "F.Cu")
		(net "SELF_TRAY_PRESENT")
	)
	(segment
		(start 155.2321 -73.1139)
		(end 155.2321 -51.816)
		(width 0.1397)
		(layer "F.Cu")
		(net "SELF_TRAY_PRESENT")
	)
	(segment
		(start 144.960086 -62.079886)
		(end 142.851886 -62.079886)
		(width 0.1397)
		(layer "F.Cu")
		(net "SELF_TRAY_PRESENT")
	)
	(segment
		(start 23.557992 -82.787744)
		(end 23.558246 -82.787998)
		(width 0.1397)
		(layer "F.Cu")
		(net "SELF_TRAY_PRESENT")
	)
	(segment
		(start 146.558 -57.785)
		(end 147.32 -58.547)
		(width 0.1397)
		(layer "F.Cu")
		(net "SELF_TRAY_PRESENT")
	)
	(segment
		(start 26.288746 -82.26679)
		(end 29.07411 -79.481426)
		(width 0.1397)
		(layer "F.Cu")
		(net "SELF_TRAY_PRESENT")
	)
	(segment
		(start 147.32 -58.547)
		(end 148.336 -58.547)
		(width 0.1397)
		(layer "F.Cu")
		(net "SELF_TRAY_PRESENT")
	)
	(segment
		(start 147.066 -60.706)
		(end 145.692114 -62.079886)
		(width 0.1397)
		(layer "F.Cu")
		(net "SELF_TRAY_PRESENT")
	)
	(segment
		(start 154.3431 -50.927)
		(end 146.685 -50.927)
		(width 0.1397)
		(layer "F.Cu")
		(net "SELF_TRAY_PRESENT")
	)
	(segment
		(start 4.080256 -82.787744)
		(end 23.557992 -82.787744)
		(width 0.1397)
		(layer "F.Cu")
		(net "SELF_TRAY_PRESENT")
	)
	(segment
		(start 136.650222 -74.487278)
		(end 136.652 -74.4855)
		(width 0.1397)
		(layer "F.Cu")
		(net "SELF_TRAY_PRESENT")
	)
	(segment
		(start 146.558 -55.245)
		(end 146.558 -57.785)
		(width 0.1397)
		(layer "F.Cu")
		(net "SELF_TRAY_PRESENT")
	)
	(segment
		(start 148.209 -60.706)
		(end 147.066 -60.706)
		(width 0.1397)
		(layer "F.Cu")
		(net "SELF_TRAY_PRESENT")
	)
	(segment
		(start 146.177 -54.864)
		(end 146.558 -55.245)
		(width 0.1397)
		(layer "F.Cu")
		(net "SELF_TRAY_PRESENT")
	)
	(via
		(at 90.955622 -79.481426)
		(size 0.7112)
		(drill 0.3556)
		(layers "F.Cu" "B.Cu")
		(net "SELF_TRAY_PRESENT")
	)
	(via
		(at 2.54 -84.328)
		(size 0.7112)
		(drill 0.4064)
		(layers "F.Cu" "B.Cu")
		(net "SELF_TRAY_PRESENT")
	)
	(segment
		(start -3.973068 -83.109308)
		(end -6.61797 -83.109308)
		(width 0.1397)
		(layer "B.Cu")
		(net "SELF_TRAY_PRESENT")
	)
	(segment
		(start -1.003808 -84.328)
		(end -1.397 -83.934808)
		(width 0.1397)
		(layer "B.Cu")
		(net "SELF_TRAY_PRESENT")
	)
	(segment
		(start 2.54 -84.328)
		(end -1.003808 -84.328)
		(width 0.1397)
		(layer "B.Cu")
		(net "SELF_TRAY_PRESENT")
	)
	(segment
		(start -3.147568 -83.934808)
		(end -3.973068 -83.109308)
		(width 0.1397)
		(layer "B.Cu")
		(net "SELF_TRAY_PRESENT")
	)
	(segment
		(start -1.397 -83.934808)
		(end -3.147568 -83.934808)
		(width 0.1397)
		(layer "B.Cu")
		(net "SELF_TRAY_PRESENT")
	)
	(segment
		(start 159.639 -18.161)
		(end 158.369 -18.161)
		(width 0.1397)
		(layer "F.Cu")
		(net "TPS2490_LED")
	)
	(segment
		(start 156.972 -18.161)
		(end 158.369 -18.161)
		(width 0.1397)
		(layer "F.Cu")
		(net "TPS2490_LED")
	)
	(segment
		(start 161.159952 -18.237962)
		(end 159.715962 -18.237962)
		(width 0.1397)
		(layer "F.Cu")
		(net "TPS2490_LED")
	)
	(segment
		(start 159.715962 -18.237962)
		(end 159.639 -18.161)
		(width 0.1397)
		(layer "F.Cu")
		(net "TPS2490_LED")
	)
	(via
		(at 158.369 -18.161)
		(size 0.7112)
		(drill 0.3556)
		(layers "F.Cu" "B.Cu")
		(net "TPS2490_LED")
	)
	(segment
		(start 8.927592 -85.835744)
		(end 8.431276 -85.835744)
		(width 0.1397)
		(layer "F.Cu")
		(net "PWM_EXP_B")
	)
	(segment
		(start 8.431276 -85.835744)
		(end 7.854442 -85.25891)
		(width 0.1397)
		(layer "F.Cu")
		(net "PWM_EXP_B")
	)
	(via
		(at 6.731 -83.930744)
		(size 0.7112)
		(drill 0.3556)
		(layers "F.Cu" "B.Cu")
		(net "PWM_EXP_B")
	)
	(via
		(at 7.854442 -85.25891)
		(size 0.7112)
		(drill 0.4064)
		(layers "F.Cu" "B.Cu")
		(net "PWM_EXP_B")
	)
	(segment
		(start 7.41426 -83.930744)
		(end 6.731 -83.930744)
		(width 0.1397)
		(layer "B.Cu")
		(net "PWM_EXP_B")
	)
	(segment
		(start -2.032 -81.839308)
		(end -0.178308 -83.693)
		(width 0.1397)
		(layer "B.Cu")
		(net "PWM_EXP_B")
	)
	(segment
		(start -6.61797 -81.839308)
		(end -2.032 -81.839308)
		(width 0.1397)
		(layer "B.Cu")
		(net "PWM_EXP_B")
	)
	(segment
		(start 5.063744 -83.930744)
		(end 6.731 -83.930744)
		(width 0.1397)
		(layer "B.Cu")
		(net "PWM_EXP_B")
	)
	(segment
		(start 4.826 -83.693)
		(end 5.063744 -83.930744)
		(width 0.1397)
		(layer "B.Cu")
		(net "PWM_EXP_B")
	)
	(segment
		(start 7.854442 -85.25891)
		(end 7.854442 -84.370926)
		(width 0.1397)
		(layer "B.Cu")
		(net "PWM_EXP_B")
	)
	(segment
		(start -0.178308 -83.693)
		(end 4.826 -83.693)
		(width 0.1397)
		(layer "B.Cu")
		(net "PWM_EXP_B")
	)
	(segment
		(start 7.854442 -84.370926)
		(end 7.41426 -83.930744)
		(width 0.1397)
		(layer "B.Cu")
		(net "PWM_EXP_B")
	)
	(segment
		(start 7.353808 -84.692744)
		(end 6.787642 -85.25891)
		(width 0.1397)
		(layer "F.Cu")
		(net "PWM_EXP_A")
	)
	(segment
		(start 8.927592 -84.692744)
		(end 7.353808 -84.692744)
		(width 0.1397)
		(layer "F.Cu")
		(net "PWM_EXP_A")
	)
	(via
		(at 3.556 -85.344)
		(size 0.7112)
		(drill 0.3556)
		(layers "F.Cu" "B.Cu")
		(net "PWM_EXP_A")
	)
	(via
		(at 6.787642 -85.25891)
		(size 0.7112)
		(drill 0.4064)
		(layers "F.Cu" "B.Cu")
		(net "PWM_EXP_A")
	)
	(segment
		(start -1.609344 -84.379308)
		(end -0.644652 -85.344)
		(width 0.1397)
		(layer "B.Cu")
		(net "PWM_EXP_A")
	)
	(segment
		(start -6.61797 -84.379308)
		(end -1.609344 -84.379308)
		(width 0.1397)
		(layer "B.Cu")
		(net "PWM_EXP_A")
	)
	(segment
		(start 6.702552 -85.344)
		(end 3.556 -85.344)
		(width 0.1397)
		(layer "B.Cu")
		(net "PWM_EXP_A")
	)
	(segment
		(start 6.787642 -85.25891)
		(end 6.702552 -85.344)
		(width 0.1397)
		(layer "B.Cu")
		(net "PWM_EXP_A")
	)
	(segment
		(start -0.644652 -85.344)
		(end 3.556 -85.344)
		(width 0.1397)
		(layer "B.Cu")
		(net "PWM_EXP_A")
	)
	(zone
		(layer "F.Cu")
		(hatch none 0.5)
		(connect_pads
			(clearance 0)
		)
		(min_thickness 0.25)
		(keepout
			(tracks allowed)
			(vias allowed)
			(pads allowed)
			(copperpour allowed)
			(footprints not_allowed)
		)
		(placement
			(enabled no)
			(sheetname "")
		)
		(fill
			(thermal_gap 0.5)
			(thermal_bridge_width 0.5)
			(island_removal_mode 0)
		)
		(polygon
			(pts
				(arc
					(start 131.659884 -118.49989)
					(mid 136.159748 -114.000026)
					(end 131.659884 -109.499908)
				)
				(arc
					(start 119.659908 -109.499908)
					(mid 115.15979 -114.000026)
					(end 119.659908 -118.49989)
				)
			)
		)
	)
	(zone
		(layer "F.Cu")
		(hatch none 0.5)
		(connect_pads
			(clearance 0)
		)
		(min_thickness 0.25)
		(keepout
			(tracks allowed)
			(vias allowed)
			(pads allowed)
			(copperpour allowed)
			(footprints not_allowed)
		)
		(placement
			(enabled no)
			(sheetname "")
		)
		(fill
			(thermal_gap 0.5)
			(thermal_bridge_width 0.5)
			(island_removal_mode 0)
		)
		(polygon
			(pts
				(arc
					(start 7.659878 -10.999978)
					(mid 12.159996 -15.500096)
					(end 7.659878 -19.99996)
				)
				(xy 0 -19.99996)
				(arc
					(start 0 -27.170126)
					(mid -0.292893 -27.877231)
					(end -0.999998 -28.170124)
				)
				(xy -9.500108 -28.170124) (xy -9.500108 -74.179938)
				(arc
					(start -0.350012 -74.179938)
					(mid 0 -74.52995)
					(end -0.350012 -74.879962)
				)
				(xy -9.500108 -74.879962) (xy -9.500108 -92.95003)
				(arc
					(start -0.999998 -92.95003)
					(mid -0.292893 -93.242923)
					(end 0 -93.950028)
				)
				(xy 0 -101.000052)
				(arc
					(start 7.659878 -101.000052)
					(mid 12.159996 -105.50017)
					(end 7.659878 -110.000034)
				)
				(xy 0 -110.000034)
				(arc
					(start 0 -119.000016)
					(mid 0.292893 -119.707121)
					(end 0.999998 -120.000014)
				)
				(arc
					(start 161.660078 -120.000014)
					(mid 162.367183 -119.707121)
					(end 162.660076 -119.000016)
				)
				(xy 162.660076 -102.14991) (xy 144.159986 -102.14991) (xy 144.159986 -96.149922)
				(arc
					(start 138.660124 -96.149922)
					(mid 137.953019 -95.857029)
					(end 137.660126 -95.149924)
				)
				(arc
					(start 137.660126 -90.849958)
					(mid 137.953019 -90.142853)
					(end 138.660124 -89.84996)
				)
				(xy 144.159986 -89.84996) (xy 144.159986 -12.850114) (xy 162.660076 -12.850114)
				(arc
					(start 162.660076 -0.999998)
					(mid 162.367183 -0.292893)
					(end 161.660078 0)
				)
				(arc
					(start 0.999998 0)
					(mid 0.292893 -0.292893)
					(end 0 -0.999998)
				)
				(xy 0 -10.999978)
			)
		)
	)
	(zone
		(net "IR_SWITCH_E")
		(layer "F.Cu")
		(hatch none 0.5)
		(connect_pads
			(clearance 0.5)
		)
		(min_thickness 0.25)
		(fill yes
			(thermal_gap 0.5)
			(thermal_bridge_width 0.5)
			(island_removal_mode 0)
		)
		(polygon
			(pts
				(xy 154.837892 -99.450144) (xy 154.964892 -99.323144) (xy 154.964892 -96.948244) (xy 151.472392 -96.948244)
				(xy 151.027892 -97.392744) (xy 137.311892 -97.392744) (xy 136.219692 -96.300544) (xy 136.219692 -87.512144)
				(xy 136.219692 -84.963) (xy 135.98271 -84.726018) (xy 135.780018 -84.726018) (xy 135.382 -84.726018)
				(xy 135.255 -84.853018) (xy 135.255 -85.217) (xy 135.128 -85.344) (xy 135.128 -85.378036) (xy 134.060692 -86.445344)
				(xy 134.060692 -97.773744) (xy 135.737092 -99.450144)
			)
		)
	)
	(zone
		(layer "F.Cu")
		(hatch none 0.5)
		(connect_pads
			(clearance 0)
		)
		(min_thickness 0.25)
		(keepout
			(tracks allowed)
			(vias allowed)
			(pads allowed)
			(copperpour allowed)
			(footprints not_allowed)
		)
		(placement
			(enabled no)
			(sheetname "")
		)
		(fill
			(thermal_gap 0.5)
			(thermal_bridge_width 0.5)
			(island_removal_mode 0)
		)
		(polygon
			(pts
				(arc
					(start 161.660078 -33.53689)
					(mid 162.367183 -33.243997)
					(end 162.660076 -32.536892)
				)
				(xy 162.660076 -12.850114) (xy 144.159986 -12.850114) (xy 144.159986 -89.84996)
				(arc
					(start 159.357314 -89.84996)
					(mid 159.646996 -89.807083)
					(end 159.911796 -89.682066)
				)
				(arc
					(start 162.214814 -88.14689)
					(mid 162.54181 -87.786674)
					(end 162.660076 -87.314786)
				)
				(arc
					(start 162.660076 -81.46288)
					(mid 162.367183 -80.755775)
					(end 161.660078 -80.462882)
				)
				(arc
					(start 158.660084 -80.462882)
					(mid 157.952979 -80.169989)
					(end 157.660086 -79.462884)
				)
				(arc
					(start 157.660086 -34.536888)
					(mid 157.952979 -33.829783)
					(end 158.660084 -33.53689)
				)
			)
		)
	)
	(zone
		(net "DETECTOR_C")
		(layer "F.Cu")
		(hatch none 0.5)
		(connect_pads
			(clearance 0.5)
		)
		(min_thickness 0.25)
		(fill yes
			(thermal_gap 0.5)
			(thermal_bridge_width 0.5)
			(island_removal_mode 0)
		)
		(polygon
			(pts
				(xy 158.75 -102.362) (xy 159.131 -101.981) (xy 159.131 -97.409) (xy 158.75 -97.028) (xy 156.21 -97.028)
				(xy 156.083 -97.155) (xy 156.083 -99.949) (xy 155.067 -100.965) (xy 155.067 -102.235) (xy 155.067 -102.616)
				(xy 155.321 -102.87) (xy 158.242 -102.87)
			)
		)
	)
	(zone
		(net "GND")
		(layer "F.Cu")
		(hatch none 0.5)
		(connect_pads
			(clearance 0.5)
		)
		(min_thickness 0.25)
		(fill yes
			(thermal_gap 0.5)
			(thermal_bridge_width 0.5)
			(island_removal_mode 0)
		)
		(polygon
			(pts
				(xy 140.064744 -47.735744) (xy 123.926092 -47.735744) (xy 118.253256 -47.735744) (xy 106.061256 -47.735744)
				(xy 104.283256 -49.513744) (xy -8.357108 -49.513744) (xy -8.458708 -49.615344) (xy -8.458708 -58.759344)
				(xy -8.306308 -58.911744) (xy -3.184652 -58.911744) (xy -3.140964 -58.955432) (xy -3.140964 -59.601862)
				(xy -3.19405 -59.654948) (xy -8.287512 -59.654948) (xy -8.433308 -59.800744) (xy -8.433308 -68.919344)
				(xy -8.282686 -69.069966) (xy -3.20294 -69.069966) (xy -3.165602 -69.107304) (xy -3.165602 -69.775832)
				(xy -3.204464 -69.814694) (xy -8.312658 -69.814694) (xy -8.433308 -69.935344) (xy -8.433308 -73.249028)
				(xy -8.27659 -73.405746) (xy 0.206756 -73.405746) (xy 0.736092 -73.935082) (xy 5.651754 -78.850744)
				(xy 24.485092 -78.850744) (xy 27.787092 -75.548744) (xy 28.01239 -75.323446) (xy 115.553236 -75.323446)
				(xy 118.369334 -75.323446) (xy 135.141716 -58.551064) (xy 136.13384 -58.551064) (xy 138.176 -58.551064)
				(xy 138.176 -58.547) (xy 140.589 -58.547) (xy 142.5575 -56.5785) (xy 142.748 -56.388) (xy 142.748 -52.324)
				(xy 142.748 -49.784) (xy 140.699744 -47.735744)
			)
		)
	)
	(zone
		(net "GND")
		(layer "F.Cu")
		(hatch none 0.5)
		(connect_pads
			(clearance 0.5)
		)
		(min_thickness 0.25)
		(fill yes
			(thermal_gap 0.5)
			(thermal_bridge_width 0.5)
			(island_removal_mode 0)
		)
		(polygon
			(pts
				(xy 1.112774 -0.813562) (xy 0.762 -1.164336) (xy 0.762 -19.558) (xy 1.397 -20.193) (xy 9.398 -20.193)
				(xy 13.716 -15.875) (xy 139.192 -15.875) (xy 147.574 -24.257) (xy 154.305 -24.257) (xy 155.702 -22.86)
				(xy 155.702 -18.542) (xy 156.083 -18.161) (xy 156.083 -17.526) (xy 156.21 -17.399) (xy 158.692342 -17.399)
				(xy 159.079692 -17.786096) (xy 160.424876 -17.786096) (xy 160.668716 -17.542256) (xy 161.656522 -17.542256)
				(xy 161.81832 -17.704054) (xy 161.81832 -18.886932) (xy 161.664396 -19.040856) (xy 160.63722 -19.040856)
				(xy 160.265364 -18.669) (xy 159.004 -18.669) (xy 158.496 -19.177) (xy 158.496 -24.892) (xy 155.321 -28.067)
				(xy 151.13 -28.067) (xy 150.749 -28.448) (xy 150.749 -35.941) (xy 155.702 -40.894) (xy 155.702 -67.945)
				(xy 153.797 -69.85) (xy 141.478 -69.85) (xy 141.097 -69.469) (xy 135.91921 -69.469) (xy 121.727214 -83.660996)
				(xy 35.634168 -83.660996) (xy 24.12492 -95.170244) (xy 20.988782 -95.170244) (xy 18.861786 -97.29724)
				(xy 18.861786 -99.502214) (xy 17.415256 -100.948744) (xy 12.674092 -100.948744) (xy 12.166092 -100.440744)
				(xy 12.166092 -99.551744) (xy 12.039092 -99.424744) (xy 11.150092 -99.424744) (xy 10.864596 -99.139248)
				(xy 8.817356 -99.139248) (xy 8.633714 -98.955606) (xy 8.633714 -97.868486) (xy 9.020556 -97.481644)
				(xy 9.989058 -97.481644) (xy 10.109962 -97.36074) (xy 10.109962 -96.10344) (xy 9.934194 -95.927672)
				(xy 8.664702 -95.927672) (xy 7.610602 -96.981772) (xy 6.642862 -96.981772) (xy 6.267704 -96.60636)
				(xy 6.267704 -95.243142) (xy 4.34467 -93.320108) (xy 4.34594 -93.318838) (xy 4.34594 -92.334842)
				(xy -0.145288 -87.843614) (xy -1.88722 -87.843614) (xy -2.565908 -88.522302) (xy -2.565908 -91.931744)
				(xy -2.438908 -92.058744) (xy -0.279908 -92.058744) (xy 0.863092 -93.201744) (xy 0.863092 -118.855744)
				(xy 1.244092 -119.236744) (xy 161.518092 -119.236744) (xy 161.864294 -118.890542) (xy 161.864294 -98.57486)
				(xy 160.832038 -97.882964) (xy 159.893 -97.882964) (xy 159.512 -98.263964) (xy 159.512 -102.743)
				(xy 158.4325 -103.8225) (xy 158.4325 -105.6005) (xy 157.861 -106.172) (xy 154.686 -106.172) (xy 154.152092 -105.638092)
				(xy 154.152092 -101.075744) (xy 153.517092 -100.440744) (xy 135.330692 -100.440744) (xy 133.044692 -98.154744)
				(xy 133.044692 -85.988144) (xy 131.605274 -84.548726) (xy 131.605274 -78.452726) (xy 133.604 -76.454)
				(xy 133.604 -74.041) (xy 134.112 -73.533) (xy 135.128 -73.533) (xy 136.779 -73.533) (xy 137.3505 -74.1045)
				(xy 137.3505 -75.7555) (xy 137.3505 -76.2635) (xy 138.811 -77.724) (xy 138.811 -82.042) (xy 139.319 -82.55)
				(xy 155.956 -82.55) (xy 155.972256 -82.533744) (xy 157.962092 -82.533744) (xy 159.359092 -83.930744)
				(xy 159.359092 -88.227662) (xy 159.554164 -88.422734) (xy 160.299146 -88.422734) (xy 161.891726 -87.357966)
				(xy 161.891726 -81.661) (xy 161.637726 -81.407) (xy 157.988 -81.407) (xy 156.845 -80.264) (xy 156.845 -76.327)
				(xy 156.845 -33.782) (xy 157.861 -32.766) (xy 161.417 -32.766) (xy 161.891726 -32.291274) (xy 161.891726 -28.448)
				(xy 161.891726 -1.03632) (xy 161.668968 -0.813562)
			)
		)
		(polygon
			(pts
				(xy 137.922 -106.68) (xy 137.541 -106.68) (xy 137.541 -107.061) (xy 137.922 -107.061)
			)
		)
		(polygon
			(pts
				(xy 137.922 -105.791) (xy 137.541 -105.791) (xy 137.541 -106.172) (xy 137.922 -106.172)
			)
		)
		(polygon
			(pts
				(xy 11.176 -100.457) (xy 10.795 -100.457) (xy 10.795 -100.838) (xy 11.176 -100.838)
			)
		)
		(polygon
			(pts
				(xy 10.16 -99.695) (xy 9.779 -99.695) (xy 9.779 -100.076) (xy 10.16 -100.076)
			)
		)
		(polygon
			(pts
				(xy 138.557 -70.231) (xy 138.176 -70.231) (xy 138.176 -70.612) (xy 138.557 -70.612)
			)
		)
		(polygon
			(pts
				(xy 137.287 -70.231) (xy 136.906 -70.231) (xy 136.906 -70.612) (xy 137.287 -70.612)
			)
		)
	)
	(zone
		(layer "F.Cu")
		(hatch none 0.5)
		(connect_pads
			(clearance 0)
		)
		(min_thickness 0.25)
		(keepout
			(tracks allowed)
			(vias allowed)
			(pads allowed)
			(copperpour allowed)
			(footprints not_allowed)
		)
		(placement
			(enabled no)
			(sheetname "")
		)
		(fill
			(thermal_gap 0.5)
			(thermal_bridge_width 0.5)
			(island_removal_mode 0)
		)
		(polygon
			(pts
				(arc
					(start 126.659894 -1.500124)
					(mid 131.160012 -6.000242)
					(end 126.659894 -10.500106)
				)
				(arc
					(start 114.659918 -10.500106)
					(mid 110.160054 -6.000242)
					(end 114.659918 -1.500124)
				)
			)
		)
	)
	(zone
		(net "GND")
		(layer "F.Cu")
		(hatch none 0.5)
		(connect_pads
			(clearance 0.5)
		)
		(min_thickness 0.25)
		(fill yes
			(thermal_gap 0.5)
			(thermal_bridge_width 0.5)
			(island_removal_mode 0)
		)
		(polygon
			(pts
				(xy 15.367 -91.567) (xy 15.367 -88.29675) (xy 14.937486 -87.867236) (xy 11.952986 -87.867236) (xy 10.313162 -89.50706)
				(xy 10.313162 -89.507314) (xy 10.233406 -89.58707) (xy 10.233406 -92.524834) (xy 10.07491 -92.68333)
				(xy 8.567166 -92.68333) (xy 8.26643 -92.382594) (xy 8.26643 -91.74988) (xy 7.594854 -91.078304)
				(xy 6.157722 -91.078304) (xy 4.392422 -89.313004) (xy 4.392422 -87.453978) (xy 5.235956 -86.610444)
				(xy 10.78103 -86.610444) (xy 11.920474 -85.471) (xy 15.748 -85.471) (xy 30.263846 -85.471) (xy 30.44825 -85.655404)
				(xy 30.44825 -86.01075) (xy 24.638 -91.821) (xy 17.907 -91.821) (xy 17.846548 -91.821) (xy 17.54505 -91.519502)
				(xy 17.54505 -91.052142) (xy 17.538954 -91.046046) (xy 17.233392 -90.740484) (xy 16.375126 -90.740484)
				(xy 16.10995 -91.00566) (xy 16.10995 -91.58605) (xy 16.002 -91.694) (xy 15.494 -91.694)
			)
		)
	)
	(zone
		(net "GND")
		(layer "F.Cu")
		(hatch none 0.5)
		(connect_pads
			(clearance 0.5)
		)
		(min_thickness 0.25)
		(fill yes
			(thermal_gap 0.5)
			(thermal_bridge_width 0.5)
			(island_removal_mode 0)
		)
		(polygon
			(pts
				(xy -3.932174 -77.644244) (xy -7.880604 -77.644244) (xy -7.887716 -77.644244) (xy -7.949184 -77.705712)
				(xy -7.949184 -77.761338) (xy -7.949184 -78.400402) (xy -7.924292 -78.425294) (xy -7.883906 -78.425294)
				(xy -7.883652 -78.42504) (xy -4.490466 -78.42504) (xy -4.470146 -78.44536) (xy -4.470146 -78.866492)
				(xy -4.496816 -78.893162) (xy -7.905496 -78.893162) (xy -7.949184 -78.93685) (xy -7.949184 -79.5909)
				(xy -7.874508 -79.665576) (xy -4.516882 -79.665576) (xy -4.516628 -79.665322) (xy -3.999738 -79.665322)
				(xy -3.023362 -79.665322) (xy -1.850644 -80.83804) (xy -0.44958 -80.83804) (xy -0.254508 -80.642968)
				(xy -0.254508 -80.483202) (xy -0.254508 -79.808578) (xy -0.445262 -79.617824) (xy -2.418842 -77.644244)
			)
		)
	)
	(zone
		(net "EMITTER_K")
		(layer "F.Cu")
		(hatch none 0.5)
		(connect_pads
			(clearance 0.5)
		)
		(min_thickness 0.25)
		(fill yes
			(thermal_gap 0.5)
			(thermal_bridge_width 0.5)
			(island_removal_mode 0)
		)
		(polygon
			(pts
				(xy 158.5722 -89.086436) (xy 158.647892 -89.010744) (xy 158.647892 -84.641944) (xy 158.647892 -84.260944)
				(xy 157.758892 -83.371944) (xy 157.377892 -83.371944) (xy 155.980892 -83.371944) (xy 139.259056 -83.371944)
				(xy 139.065 -83.566) (xy 139.065 -84.709) (xy 139.065 -84.963) (xy 139.192 -85.09) (xy 155.448 -85.09)
				(xy 155.575 -85.217) (xy 155.853892 -85.495892) (xy 155.853892 -89.010744) (xy 155.929584 -89.086436)
			)
		)
	)
	(zone
		(layer "F.Cu")
		(hatch none 0.5)
		(connect_pads
			(clearance 0)
		)
		(min_thickness 0.25)
		(keepout
			(tracks allowed)
			(vias allowed)
			(pads allowed)
			(copperpour allowed)
			(footprints not_allowed)
		)
		(placement
			(enabled no)
			(sheetname "")
		)
		(fill
			(thermal_gap 0.5)
			(thermal_bridge_width 0.5)
			(island_removal_mode 0)
		)
		(polygon
			(pts
				(arc
					(start 7.659878 -10.999978)
					(mid 12.159996 -15.500096)
					(end 7.659878 -19.99996)
				)
				(xy 0 -19.99996) (xy 0 -10.999978)
			)
		)
	)
	(zone
		(net "P3V3")
		(layer "F.Cu")
		(hatch none 0.5)
		(connect_pads
			(clearance 0.5)
		)
		(min_thickness 0.25)
		(fill yes
			(thermal_gap 0.5)
			(thermal_bridge_width 0.5)
			(island_removal_mode 0)
		)
		(polygon
			(pts
				(xy 151.993092 -89.010744) (xy 152.755092 -89.010744) (xy 153.085292 -89.010744) (xy 153.263092 -89.010744)
				(xy 154.990292 -89.010744) (xy 155.345892 -88.655144) (xy 155.345892 -86.106) (xy 154.952446 -85.712554)
				(xy 154.774392 -85.5345) (xy 150.802848 -85.5345) (xy 150.485348 -85.852) (xy 150.485348 -87.503)
				(xy 150.485348 -88.636348) (xy 150.859744 -89.010744)
			)
		)
	)
	(zone
		(layer "F.Cu")
		(hatch none 0.5)
		(connect_pads
			(clearance 0)
		)
		(min_thickness 0.25)
		(keepout
			(tracks allowed)
			(vias allowed)
			(pads allowed)
			(copperpour allowed)
			(footprints not_allowed)
		)
		(placement
			(enabled no)
			(sheetname "")
		)
		(fill
			(thermal_gap 0.5)
			(thermal_bridge_width 0.5)
			(island_removal_mode 0)
		)
		(polygon
			(pts
				(arc
					(start 7.659878 -101.000052)
					(mid 12.159996 -105.50017)
					(end 7.659878 -110.000034)
				)
				(xy 0 -110.000034) (xy 0 -101.000052)
			)
		)
	)
	(zone
		(layer "F.Cu")
		(hatch none 0.5)
		(connect_pads
			(clearance 0)
		)
		(min_thickness 0.25)
		(keepout
			(tracks allowed)
			(vias allowed)
			(pads allowed)
			(copperpour allowed)
			(footprints not_allowed)
		)
		(placement
			(enabled no)
			(sheetname "")
		)
		(fill
			(thermal_gap 0.5)
			(thermal_bridge_width 0.5)
			(island_removal_mode 0)
		)
		(polygon
			(pts
				(xy 144.159986 -102.14991) (xy 144.159986 -96.149922)
				(arc
					(start 159.357314 -96.149922)
					(mid 159.647001 -96.192954)
					(end 159.911796 -96.31807)
				)
				(arc
					(start 162.214814 -97.853246)
					(mid 162.54175 -98.21335)
					(end 162.660076 -98.685096)
				)
				(xy 162.660076 -102.14991)
			)
		)
	)
	(zone
		(layer "F.Cu")
		(hatch none 0.5)
		(connect_pads
			(clearance 0)
		)
		(min_thickness 0.25)
		(keepout
			(tracks allowed)
			(vias allowed)
			(pads allowed)
			(copperpour allowed)
			(footprints not_allowed)
		)
		(placement
			(enabled no)
			(sheetname "")
		)
		(fill
			(thermal_gap 0.5)
			(thermal_bridge_width 0.5)
			(island_removal_mode 0)
		)
		(polygon
			(pts
				(arc
					(start 6.379972 -63.5)
					(mid 7.087077 -63.207107)
					(end 7.37997 -62.500002)
				)
				(arc
					(start 7.37997 -57.500012)
					(mid 7.087077 -56.792907)
					(end 6.379972 -56.500014)
				)
				(arc
					(start 5.379974 -56.500014)
					(mid 4.672869 -56.792907)
					(end 4.379976 -57.500012)
				)
				(arc
					(start 4.379976 -62.500002)
					(mid 4.672869 -63.207107)
					(end 5.379974 -63.5)
				)
			)
		)
	)
	(zone
		(net "P12V")
		(layer "F.Cu")
		(hatch none 0.5)
		(connect_pads
			(clearance 0.5)
		)
		(min_thickness 0.25)
		(fill yes
			(thermal_gap 0.5)
			(thermal_bridge_width 0.5)
			(island_removal_mode 0)
		)
		(polygon
			(pts
				(xy 123.291092 -46.973744) (xy 124.434092 -46.973744) (xy 140.826744 -46.973744) (xy 140.843 -46.99)
				(xy 141.224 -46.99) (xy 144.272 -50.038) (xy 153.797 -50.038) (xy 154.432 -49.403) (xy 154.432 -41.148)
				(xy 149.606 -36.322) (xy 149.606 -29.972) (xy 149.606 -28.321) (xy 150.368 -27.559) (xy 155.194 -27.559)
				(xy 157.988 -24.765) (xy 157.988 -24.13) (xy 157.988 -19.431) (xy 157.988 -19.304) (xy 157.861 -19.177)
				(xy 157.734 -19.177) (xy 156.337 -19.177) (xy 156.21 -19.304) (xy 156.21 -23.241) (xy 154.559 -24.892)
				(xy 147.828 -24.892) (xy 147.447 -24.892) (xy 138.921744 -16.366744) (xy 127.990092 -16.366744)
				(xy 14.351 -16.366744) (xy 9.635744 -21.082) (xy 1.397 -21.082) (xy 0.762 -21.717) (xy 0.762 -22.86)
				(xy 0.762 -28.151836) (xy -0.233934 -29.14777) (xy -7.8359 -29.14777) (xy -7.839964 -29.152088)
				(xy -8.366252 -29.152088) (xy -8.458708 -29.244544) (xy -8.458708 -38.413944) (xy -8.291068 -38.581584)
				(xy -3.198876 -38.581584) (xy -3.130804 -38.649656) (xy -3.130804 -39.252906) (xy -3.21183 -39.333932)
				(xy -8.388096 -39.333932) (xy -8.458708 -39.404544) (xy -8.458708 -48.624744) (xy -8.325612 -48.75784)
				(xy 103.89616 -48.75784) (xy 105.680256 -46.973744) (xy 117.735096 -46.973744)
			)
		)
	)
	(zone
		(layer "F.Cu")
		(hatch none 0.5)
		(connect_pads
			(clearance 0)
		)
		(min_thickness 0.25)
		(keepout
			(tracks allowed)
			(vias allowed)
			(pads allowed)
			(copperpour allowed)
			(footprints not_allowed)
		)
		(placement
			(enabled no)
			(sheetname "")
		)
		(fill
			(thermal_gap 0.5)
			(thermal_bridge_width 0.5)
			(island_removal_mode 0)
		)
		(polygon
			(pts
				(arc
					(start 131.659884 -109.499908)
					(mid 136.160002 -114.000026)
					(end 131.659884 -118.49989)
				)
				(arc
					(start 119.659908 -118.49989)
					(mid 115.160044 -114.000026)
					(end 119.659908 -109.499908)
				)
			)
		)
	)
	(zone
		(layers "F.Cu" "B.Cu" "In1.Cu" "In2.Cu")
		(hatch none 0.5)
		(connect_pads
			(clearance 0)
		)
		(min_thickness 0.25)
		(keepout
			(tracks not_allowed)
			(vias allowed)
			(pads allowed)
			(copperpour not_allowed)
			(footprints allowed)
		)
		(placement
			(enabled no)
			(sheetname "")
		)
		(fill
			(thermal_gap 0.5)
			(thermal_bridge_width 0.5)
			(island_removal_mode 0)
		)
		(polygon
			(pts
				(arc
					(start 8.14197 -57.500012)
					(mid 7.625893 -56.254091)
					(end 6.379972 -55.738014)
				)
				(arc
					(start 5.379974 -55.738014)
					(mid 4.134053 -56.254091)
					(end 3.617976 -57.500012)
				)
				(arc
					(start 3.617976 -62.500002)
					(mid 4.134053 -63.745923)
					(end 5.379974 -64.262)
				)
				(arc
					(start 6.379972 -64.262)
					(mid 7.625893 -63.745923)
					(end 8.14197 -62.500002)
				)
			)
		)
	)
	(zone
		(layers "F.Cu" "B.Cu" "In1.Cu" "In2.Cu")
		(name "Package Keepin")
		(hatch none 0.5)
		(connect_pads
			(clearance 0)
		)
		(min_thickness 0.25)
		(keepout
			(tracks allowed)
			(vias allowed)
			(pads allowed)
			(copperpour allowed)
			(footprints allowed)
		)
		(placement
			(enabled no)
			(sheetname "")
		)
		(fill
			(thermal_gap 0.5)
			(thermal_bridge_width 0.5)
			(island_removal_mode 0)
		)
		(polygon
			(pts
				(xy 3.9878 -3.9878)
				(arc
					(start 3.9878 -27.170126)
					(mid 2.526908 -30.697032)
					(end -0.999998 -32.157924)
				)
				(xy -7.012178 -32.157924) (xy -7.012178 -70.192138)
				(arc
					(start -0.350012 -70.192138)
					(mid 3.9878 -74.52995)
					(end -0.350012 -78.867762)
				)
				(xy -7.012178 -78.867762) (xy -7.012178 -88.96223)
				(arc
					(start -0.999998 -88.96223)
					(mid 2.526908 -90.423122)
					(end 3.9878 -93.950028)
				)
				(xy 3.9878 -116.012214) (xy 158.672276 -116.012214) (xy 158.672276 -100.28428) (xy 158.452312 -100.137722)
				(arc
					(start 138.660124 -100.137722)
					(mid 135.133218 -98.67683)
					(end 133.672326 -95.149924)
				)
				(arc
					(start 133.672326 -90.849958)
					(mid 135.133218 -87.323052)
					(end 138.660124 -85.86216)
				)
				(xy 158.452566 -85.86216) (xy 158.672276 -85.715856) (xy 158.672276 -84.450682)
				(arc
					(start 158.660084 -84.450682)
					(mid 155.133178 -82.98979)
					(end 153.672286 -79.462884)
				)
				(arc
					(start 153.672286 -34.536888)
					(mid 155.133178 -31.009982)
					(end 158.660084 -29.54909)
				)
				(xy 158.672276 -29.54909) (xy 158.672276 -3.9878)
			)
		)
	)
	(zone
		(layers "F.Cu" "B.Cu" "In1.Cu" "In2.Cu")
		(name "Route Keepin")
		(hatch none 0.5)
		(connect_pads
			(clearance 0)
		)
		(min_thickness 0.25)
		(keepout
			(tracks allowed)
			(vias allowed)
			(pads allowed)
			(copperpour allowed)
			(footprints allowed)
		)
		(placement
			(enabled no)
			(sheetname "")
		)
		(fill
			(thermal_gap 0.5)
			(thermal_bridge_width 0.5)
			(island_removal_mode 0)
		)
		(polygon
			(pts
				(arc
					(start 161.898076 -0.999998)
					(mid 161.828368 -0.831708)
					(end 161.660078 -0.762)
				)
				(arc
					(start 0.999998 -0.762)
					(mid 0.831708 -0.831708)
					(end 0.762 -0.999998)
				)
				(arc
					(start 0.762 -27.170126)
					(mid 0.245923 -28.416047)
					(end -0.999998 -28.932124)
				)
				(xy -9.184386 -28.932124) (xy -10.237978 -29.985716) (xy -10.237978 -72.364346) (xy -9.184386 -73.417938)
				(arc
					(start -0.350012 -73.417938)
					(mid 0.762 -74.52995)
					(end -0.350012 -75.641962)
				)
				(xy -9.184386 -75.641962) (xy -10.237978 -76.695554) (xy -10.237978 -91.134438) (xy -9.184386 -92.18803)
				(arc
					(start -0.999998 -92.18803)
					(mid 0.245923 -92.704107)
					(end 0.762 -93.950028)
				)
				(arc
					(start 0.762 -119.000016)
					(mid 0.831708 -119.168306)
					(end 0.999998 -119.238014)
				)
				(arc
					(start 161.660078 -119.238014)
					(mid 161.828368 -119.168306)
					(end 161.898076 -119.000016)
				)
				(arc
					(start 161.898076 -98.685096)
					(mid 161.869855 -98.572937)
					(end 161.792158 -98.48723)
				)
				(arc
					(start 159.488886 -96.952054)
					(mid 159.425944 -96.922218)
					(end 159.35706 -96.911922)
				)
				(arc
					(start 138.660124 -96.911922)
					(mid 137.414203 -96.395845)
					(end 136.898126 -95.149924)
				)
				(arc
					(start 136.898126 -90.849958)
					(mid 137.414203 -89.604037)
					(end 138.660124 -89.08796)
				)
				(arc
					(start 159.357314 -89.08796)
					(mid 159.426181 -89.077779)
					(end 159.48914 -89.048082)
				)
				(arc
					(start 161.792158 -87.512906)
					(mid 161.870014 -87.42714)
					(end 161.898076 -87.314786)
				)
				(arc
					(start 161.898076 -81.46288)
					(mid 161.828368 -81.29459)
					(end 161.660078 -81.224882)
				)
				(arc
					(start 158.660084 -81.224882)
					(mid 157.414163 -80.708805)
					(end 156.898086 -79.462884)
				)
				(arc
					(start 156.898086 -34.536888)
					(mid 157.414163 -33.290967)
					(end 158.660084 -32.77489)
				)
				(arc
					(start 161.660078 -32.77489)
					(mid 161.828368 -32.705182)
					(end 161.898076 -32.536892)
				)
			)
		)
	)
	(zone
		(layer "B.Cu")
		(hatch none 0.5)
		(connect_pads
			(clearance 0)
		)
		(min_thickness 0.25)
		(keepout
			(tracks allowed)
			(vias allowed)
			(pads allowed)
			(copperpour allowed)
			(footprints not_allowed)
		)
		(placement
			(enabled no)
			(sheetname "")
		)
		(fill
			(thermal_gap 0.5)
			(thermal_bridge_width 0.5)
			(island_removal_mode 0)
		)
		(polygon
			(pts
				(xy 0 -3.999992) (xy 0 -116.000022) (xy 15.999968 -116.000022) (xy 15.999968 -3.999992)
			)
		)
	)
	(zone
		(layer "B.Cu")
		(hatch none 0.5)
		(connect_pads
			(clearance 0)
		)
		(min_thickness 0.25)
		(keepout
			(tracks allowed)
			(vias allowed)
			(pads allowed)
			(copperpour allowed)
			(footprints not_allowed)
		)
		(placement
			(enabled no)
			(sheetname "")
		)
		(fill
			(thermal_gap 0.5)
			(thermal_bridge_width 0.5)
			(island_removal_mode 0)
		)
		(polygon
			(pts
				(arc
					(start 136.160002 -114.000026)
					(mid 131.660138 -109.500162)
					(end 127.16002 -114.000026)
				)
				(arc
					(start 127.16002 -114.000026)
					(mid 131.660138 -118.500144)
					(end 136.160002 -114.000026)
				)
			)
		)
	)
	(zone
		(net "P12V")
		(layer "B.Cu")
		(hatch none 0.5)
		(connect_pads
			(clearance 0.5)
		)
		(min_thickness 0.25)
		(fill yes
			(thermal_gap 0.5)
			(thermal_bridge_width 0.5)
			(island_removal_mode 0)
		)
		(polygon
			(pts
				(xy 154.432 -45.466) (xy 154.432 -44.958) (xy 154.432 -41.148) (xy 149.987 -36.703) (xy 149.606 -36.322)
				(xy 149.606 -36.195) (xy 149.606 -27.051) (xy 138.921744 -16.366744) (xy 127.990092 -16.366744)
				(xy 14.351 -16.366744) (xy 11.159744 -19.558) (xy 10.143744 -20.574) (xy 9.889744 -20.828) (xy 1.498092 -20.828)
				(xy 0.863092 -21.463) (xy 0.863092 -22.352) (xy 0.863092 -23.097744) (xy 0.863092 -28.050744) (xy -0.233934 -29.14777)
				(xy -7.8359 -29.14777) (xy -7.839964 -29.152088) (xy -8.366252 -29.152088) (xy -8.458708 -29.244544)
				(xy -8.458708 -38.413944) (xy -8.291068 -38.581584) (xy -3.198876 -38.581584) (xy -3.130804 -38.649656)
				(xy -3.130804 -39.252906) (xy -3.21183 -39.333932) (xy -8.388096 -39.333932) (xy -8.458708 -39.404544)
				(xy -8.458708 -48.624744) (xy -8.325612 -48.75784) (xy 103.886 -48.75784) (xy 105.65384 -46.99)
				(xy 141.097 -46.99) (xy 144.145 -50.038) (xy 153.797 -50.038) (xy 154.432 -49.403) (xy 154.432 -48.514)
			)
		)
	)
	(zone
		(layer "B.Cu")
		(hatch none 0.5)
		(connect_pads
			(clearance 0)
		)
		(min_thickness 0.25)
		(keepout
			(tracks allowed)
			(vias allowed)
			(pads allowed)
			(copperpour allowed)
			(footprints not_allowed)
		)
		(placement
			(enabled no)
			(sheetname "")
		)
		(fill
			(thermal_gap 0.5)
			(thermal_bridge_width 0.5)
			(island_removal_mode 0)
		)
		(polygon
			(pts
				(arc
					(start 131.160012 -5.999988)
					(mid 126.660148 -1.500124)
					(end 122.16003 -5.999988)
				)
				(arc
					(start 122.16003 -5.999988)
					(mid 126.660148 -10.500106)
					(end 131.160012 -5.999988)
				)
			)
		)
	)
	(zone
		(net "P3V3")
		(layer "B.Cu")
		(hatch none 0.5)
		(connect_pads
			(clearance 0.5)
		)
		(min_thickness 0.25)
		(fill yes
			(thermal_gap 0.5)
			(thermal_bridge_width 0.5)
			(island_removal_mode 0)
		)
		(polygon
			(pts
				(xy 1.625092 -77.622654) (xy 0.135382 -77.622654) (xy -0.230378 -77.622654) (xy -0.799338 -77.622654)
				(xy -0.846074 -77.622654) (xy -4.440682 -77.622654) (xy -4.444746 -77.626718) (xy -7.87908 -77.626718)
				(xy -7.94131 -77.688948) (xy -7.94131 -78.367636) (xy -7.894574 -78.414372) (xy -4.49326 -78.414372)
				(xy -4.459224 -78.448408) (xy -4.459224 -78.880716) (xy -4.482338 -78.90383) (xy -7.900924 -78.90383)
				(xy -7.94131 -78.944216) (xy -7.94131 -79.570326) (xy -7.841742 -79.669894) (xy -4.507738 -79.669894)
				(xy -0.408178 -79.669894) (xy -0.108458 -79.969614) (xy 1.117092 -79.969614) (xy 2.728722 -81.581244)
				(xy 8.673592 -81.581244) (xy 11.531092 -84.438744) (xy 11.531092 -95.106744) (xy 9.144 -97.493836)
				(xy 9.144 -98.552) (xy 9.398 -98.806) (xy 10.303256 -98.806) (xy 10.795 -98.806) (xy 13.462 -101.473)
				(xy 13.572744 -101.583744) (xy 13.699744 -101.583744) (xy 15.595092 -101.583744) (xy 129.606548 -101.583744)
				(xy 133.086348 -105.063544) (xy 155.218892 -105.063544) (xy 155.752292 -105.063544) (xy 155.930092 -104.885744)
				(xy 155.930092 -101.456744) (xy 155.422092 -100.948744) (xy 137.261092 -100.948744) (xy 133.705092 -97.392744)
				(xy 133.705092 -89.010744) (xy 135.610092 -87.105744) (xy 136.372092 -87.105744) (xy 154.787092 -87.105744)
				(xy 155.231592 -86.661244) (xy 155.231592 -83.232244) (xy 155.231592 -82.851244) (xy 154.914092 -82.533744)
				(xy 146.151092 -82.533744) (xy 145.262092 -81.644744) (xy 145.262092 -79.612744) (xy 145.008092 -79.358744)
				(xy 136.372092 -79.358744) (xy 133.959092 -81.771744) (xy 129.514092 -86.216744) (xy 127.863092 -87.867744)
				(xy 127.863092 -96.757744) (xy 127.355092 -97.265744) (xy 21.564092 -97.265744) (xy 16.992092 -97.265744)
				(xy 14.960092 -95.233744) (xy 14.960092 -80.247744) (xy 12.335002 -77.622654) (xy 10.557002 -77.622654)
			)
		)
	)
	(zone
		(layer "B.Cu")
		(hatch none 0.5)
		(connect_pads
			(clearance 0)
		)
		(min_thickness 0.25)
		(keepout
			(tracks allowed)
			(vias allowed)
			(pads allowed)
			(copperpour allowed)
			(footprints not_allowed)
		)
		(placement
			(enabled no)
			(sheetname "")
		)
		(fill
			(thermal_gap 0.5)
			(thermal_bridge_width 0.5)
			(island_removal_mode 0)
		)
		(polygon
			(pts
				(arc
					(start 122.16003 -5.999988)
					(mid 126.660148 -10.500106)
					(end 131.160012 -5.999988)
				)
				(arc
					(start 131.160012 -5.999988)
					(mid 126.660148 -1.500124)
					(end 122.16003 -5.999988)
				)
			)
		)
	)
	(zone
		(layer "B.Cu")
		(hatch none 0.5)
		(connect_pads
			(clearance 0)
		)
		(min_thickness 0.25)
		(keepout
			(tracks allowed)
			(vias allowed)
			(pads allowed)
			(copperpour allowed)
			(footprints not_allowed)
		)
		(placement
			(enabled no)
			(sheetname "")
		)
		(fill
			(thermal_gap 0.5)
			(thermal_bridge_width 0.5)
			(island_removal_mode 0)
		)
		(polygon
			(pts
				(arc
					(start 161.660078 -120.000014)
					(mid 162.367183 -119.707121)
					(end 162.660076 -119.000016)
				)
				(arc
					(start 162.660076 -98.685096)
					(mid 162.541691 -98.213381)
					(end 162.214814 -97.853246)
				)
				(arc
					(start 159.911796 -96.31807)
					(mid 159.647 -96.192958)
					(end 159.357314 -96.149922)
				)
				(arc
					(start 138.660124 -96.149922)
					(mid 137.953019 -95.857029)
					(end 137.660126 -95.149924)
				)
				(arc
					(start 137.660126 -90.849958)
					(mid 137.953019 -90.142853)
					(end 138.660124 -89.84996)
				)
				(arc
					(start 159.357314 -89.84996)
					(mid 159.646996 -89.807083)
					(end 159.911796 -89.682066)
				)
				(arc
					(start 162.214814 -88.14689)
					(mid 162.54181 -87.786674)
					(end 162.660076 -87.314786)
				)
				(arc
					(start 162.660076 -81.46288)
					(mid 162.367183 -80.755775)
					(end 161.660078 -80.462882)
				)
				(arc
					(start 158.660084 -80.462882)
					(mid 157.952979 -80.169989)
					(end 157.660086 -79.462884)
				)
				(arc
					(start 157.660086 -34.536888)
					(mid 157.952979 -33.829783)
					(end 158.660084 -33.53689)
				)
				(arc
					(start 161.660078 -33.53689)
					(mid 162.367183 -33.243997)
					(end 162.660076 -32.536892)
				)
				(arc
					(start 162.660076 -0.999998)
					(mid 162.367183 -0.292893)
					(end 161.660078 0)
				)
				(arc
					(start 0.999998 0)
					(mid 0.292893 -0.292893)
					(end 0 -0.999998)
				)
				(xy 0 -3.999992) (xy 15.999968 -3.999992) (xy 15.999968 -116.000022) (xy 0 -116.000022)
				(arc
					(start 0 -119.000016)
					(mid 0.292893 -119.707121)
					(end 0.999998 -120.000014)
				)
			)
		)
	)
	(zone
		(net "GND")
		(layer "B.Cu")
		(hatch none 0.5)
		(connect_pads
			(clearance 0.5)
		)
		(min_thickness 0.25)
		(fill yes
			(thermal_gap 0.5)
			(thermal_bridge_width 0.5)
			(island_removal_mode 0)
		)
		(polygon
			(pts
				(xy 161.518092 -119.236744) (xy 161.863024 -118.891812) (xy 161.863024 -98.563176) (xy 159.535114 -97.011744)
				(arc
					(start 138.658092 -97.011744)
					(mid 137.400856 -96.49098)
					(end 136.880092 -95.233744)
				)
				(arc
					(start 136.880092 -90.788744)
					(mid 137.400856 -89.531508)
					(end 138.658092 -89.010744)
				)
				(xy 159.507174 -89.010744) (xy 161.844482 -87.460836) (xy 161.844482 -81.534) (xy 161.590482 -81.28)
				(xy 157.861 -81.28) (xy 156.845 -80.264) (xy 156.845 -76.327) (xy 156.845 -53.467) (xy 156.845 -33.782)
				(xy 157.861 -32.766) (xy 161.544 -32.766) (xy 161.844482 -32.465518) (xy 161.844482 -28.448) (xy 161.844482 -0.989076)
				(xy 161.668968 -0.813562) (xy 1.112774 -0.813562) (xy 0.883666 -1.04267) (xy 0.883666 -15.731744)
				(xy 0.883666 -18.917666) (xy 0.889 -18.923) (xy 0.889 -19.939) (xy 1.016 -20.066) (xy 9.652 -20.066)
				(xy 10.7315 -18.9865) (xy 13.859256 -15.858744) (xy 128.244092 -15.858744) (xy 139.18184 -15.858744)
				(xy 150.622 -27.298904) (xy 150.622 -30.353) (xy 151.257 -30.988) (xy 152.527 -32.258) (xy 154.051 -32.258)
				(xy 154.432 -32.639) (xy 155.956 -34.163) (xy 155.956 -47.371) (xy 155.956 -52.324) (xy 154.813 -53.467)
				(xy 151.765 -53.467) (xy 149.86 -55.372) (xy 144.78 -55.372) (xy 144.399 -55.372) (xy 143.9545 -54.9275)
				(xy 143.9545 -54.1655) (xy 143.9545 -50.9905) (xy 143.891 -50.927) (xy 142.477744 -49.513744) (xy 140.716 -47.752)
				(xy 106.045 -47.752) (xy 104.283256 -49.513744) (xy 104.267 -49.513744) (xy -8.357108 -49.513744)
				(xy -8.458708 -49.615344) (xy -8.458708 -58.759344) (xy -8.306308 -58.911744) (xy -3.184652 -58.911744)
				(xy -3.140964 -58.955432) (xy -3.140964 -59.601862) (xy -3.19405 -59.654948) (xy -8.287512 -59.654948)
				(xy -8.433308 -59.800744) (xy -8.433308 -68.919344) (xy -8.282686 -69.069966) (xy -3.20294 -69.069966)
				(xy -3.165602 -69.107304) (xy -3.165602 -69.775832) (xy -3.204464 -69.814694) (xy -8.312658 -69.814694)
				(xy -8.433308 -69.935344) (xy -8.433308 -73.252076) (xy -8.269478 -73.415906) (xy 0.22606 -73.415906)
				(xy 0.863092 -74.052938) (xy 0.863092 -74.697082) (xy 0.863092 -75.675744) (xy 0.228092 -76.310744)
				(xy -0.914908 -76.310744) (xy -1.041908 -76.437744) (xy -1.041908 -76.945744) (xy -0.914908 -77.072744)
				(xy 12.801092 -77.072744) (xy 15.468092 -79.739744) (xy 15.468092 -94.725744) (xy 17.373092 -96.630744)
				(xy 22.072092 -96.630744) (xy 126.339092 -96.630744) (xy 127.101092 -95.868744) (xy 127.101092 -87.486744)
				(xy 135.991092 -78.596744) (xy 145.262092 -78.596744) (xy 145.770092 -79.104744) (xy 145.897092 -79.231744)
				(xy 145.897092 -81.263744) (xy 146.405092 -81.771744) (xy 155.549092 -81.771744) (xy 156.184092 -82.406744)
				(xy 156.184092 -87.486744) (xy 155.930092 -87.740744) (xy 135.737092 -87.740744) (xy 134.340092 -89.137744)
				(xy 134.340092 -97.138744) (xy 137.642092 -100.440744) (xy 155.803092 -100.440744) (xy 156.565092 -101.202744)
				(xy 156.565092 -103.488744) (xy 156.819092 -103.742744) (xy 157.962092 -103.742744) (xy 158.216092 -103.996744)
				(xy 158.216092 -105.266744) (xy 158.216092 -105.816908) (xy 156.480256 -107.552744) (xy 155.930092 -107.552744)
				(xy 132.079492 -107.552744) (xy 128.142492 -103.615744) (xy 16.865092 -103.615744) (xy 14.452092 -103.615744)
				(xy 12.446 -103.615744) (xy 11.641836 -103.615744) (xy 8.864092 -100.838) (xy 7.099046 -99.072954)
				(xy 6.832092 -98.806) (xy 6.832092 -91.677744) (xy 4.292092 -89.137744) (xy 0.872236 -89.137744)
				(xy 0.110236 -89.899744) (xy -0.787908 -89.899744) (xy -2.311908 -89.899744) (xy -2.565908 -90.153744)
				(xy -2.565908 -91.931744) (xy -2.438908 -92.058744)
				(arc
					(start -0.914908 -92.058744)
					(mid 0.334043 -92.496592)
					(end 0.863092 -93.709744)
				)
				(xy 0.863092 -118.855744) (xy 1.244092 -119.236744)
			)
		)
	)
	(zone
		(net "P12V")
		(layer "In1.Cu")
		(hatch none 0.5)
		(connect_pads
			(clearance 0.5)
		)
		(min_thickness 0.25)
		(fill yes
			(thermal_gap 0.5)
			(thermal_bridge_width 0.5)
			(island_removal_mode 0)
		)
		(polygon
			(pts
				(xy 138.944604 -16.36776) (xy 14.224 -16.383) (xy 14.202156 -16.383) (xy 9.884156 -20.701) (xy 0.763016 -20.701)
				(arc
					(start 0.763016 -27.170126)
					(mid 0.246641 -28.416765)
					(end -0.999998 -28.93314)
				)
				(xy -8.459978 -28.93314) (xy -8.459978 -48.87976) (xy 104.161844 -48.895) (xy 105.939844 -47.117)
				(xy 141.075156 -47.117) (xy 143.996156 -50.038) (xy 153.691844 -50.038) (xy 154.305 -49.424844)
				(xy 154.305 -40.999156) (xy 149.606 -36.300156) (xy 149.606 -27.029156)
			)
		)
	)
	(zone
		(net "GND")
		(layer "In1.Cu")
		(hatch none 0.5)
		(connect_pads
			(clearance 0.5)
		)
		(min_thickness 0.25)
		(fill yes
			(thermal_gap 0.5)
			(thermal_bridge_width 0.5)
			(island_removal_mode 0)
		)
		(polygon
			(pts
				(arc
					(start 0.999998 -0.763016)
					(mid 0.832426 -0.832426)
					(end 0.763016 -0.999998)
				)
				(xy 0.763016 -20.193) (xy 9.673844 -20.193) (xy 13.991844 -15.875) (xy 14.224 -15.875) (xy 139.154916 -15.85976)
				(xy 150.114 -26.818844) (xy 150.114 -36.089844) (xy 154.813 -40.788844) (xy 154.813 -49.635156)
				(xy 153.902156 -50.546) (xy 143.785844 -50.546) (xy 140.864844 -47.625) (xy 106.150156 -47.625)
				(xy 104.372156 -49.403) (xy -8.459978 -49.38776) (xy -8.459978 -73.416922)
				(arc
					(start -0.350012 -73.416922)
					(mid 0.763016 -74.52995)
					(end -0.350012 -75.642978)
				)
				(xy -8.459978 -75.642978) (xy -8.459978 -92.187014)
				(arc
					(start -0.999998 -92.187014)
					(mid 0.246641 -92.703389)
					(end 0.763016 -93.950028)
				)
				(arc
					(start 0.763016 -119.000016)
					(mid 0.832426 -119.167588)
					(end 0.999998 -119.236998)
				)
				(arc
					(start 161.660078 -119.236998)
					(mid 161.82765 -119.167588)
					(end 161.89706 -119.000016)
				)
				(arc
					(start 161.89706 -98.685096)
					(mid 161.869052 -98.573336)
					(end 161.79165 -98.487992)
				)
				(arc
					(start 159.488378 -96.952816)
					(mid 159.425669 -96.923162)
					(end 159.35706 -96.912938)
				)
				(arc
					(start 138.65987 -96.912938)
					(mid 137.413485 -96.396563)
					(end 136.89711 -95.150178)
				)
				(arc
					(start 136.89711 -90.849958)
					(mid 137.413485 -89.603319)
					(end 138.660124 -89.086944)
				)
				(arc
					(start 159.357314 -89.086944)
					(mid 159.425887 -89.076806)
					(end 159.488632 -89.04732)
				)
				(arc
					(start 161.79165 -87.512144)
					(mid 161.869054 -87.4268)
					(end 161.89706 -87.31504)
				)
				(arc
					(start 161.89706 -81.46288)
					(mid 161.82765 -81.295308)
					(end 161.660078 -81.225898)
				)
				(arc
					(start 158.65983 -81.225898)
					(mid 157.413445 -80.709523)
					(end 156.89707 -79.463138)
				)
				(arc
					(start 156.89707 -34.536888)
					(mid 157.413445 -33.290249)
					(end 158.660084 -32.773874)
				)
				(arc
					(start 161.660078 -32.773874)
					(mid 161.82765 -32.704464)
					(end 161.89706 -32.536892)
				)
				(arc
					(start 161.89706 -0.999998)
					(mid 161.82765 -0.832426)
					(end 161.660078 -0.763016)
				)
			)
		)
	)
	(zone
		(net "P12V")
		(layer "In2.Cu")
		(hatch none 0.5)
		(connect_pads
			(clearance 0.5)
		)
		(min_thickness 0.25)
		(fill yes
			(thermal_gap 0.5)
			(thermal_bridge_width 0.5)
			(island_removal_mode 0)
		)
		(polygon
			(pts
				(xy 138.944604 -16.36776) (xy 14.224 -16.383) (xy 14.202156 -16.383) (xy 9.884156 -20.701) (xy 1.27 -20.701)
				(arc
					(start 1.27 -27.170126)
					(mid 0.807777 -28.54302)
					(end -0.390652 -29.356812)
				)
				(xy -0.473964 -29.440124) (xy -8.459978 -29.440124) (xy -8.459978 -48.87976) (xy 104.161844 -48.895)
				(xy 105.93959 -47.117) (xy 123.670822 -47.10176) (xy 141.07541 -47.117) (xy 143.996156 -50.038)
				(xy 153.691844 -50.038) (xy 154.305 -49.424844) (xy 154.305 -40.999156) (xy 149.606 -36.300156)
				(xy 149.606 -27.029156)
			)
		)
	)
	(zone
		(net "GND")
		(layer "In2.Cu")
		(hatch none 0.5)
		(connect_pads
			(clearance 0.5)
		)
		(min_thickness 0.25)
		(fill yes
			(thermal_gap 0.5)
			(thermal_bridge_width 0.5)
			(island_removal_mode 0)
		)
		(polygon
			(pts
				(arc
					(start 1.247648 -0.763016)
					(mid 1.26439 -0.880982)
					(end 1.27 -0.999998)
				)
				(xy 1.27 -20.193) (xy 9.673844 -20.193) (xy 13.991844 -15.875) (xy 14.224 -15.875) (xy 139.154916 -15.85976)
				(xy 150.114 -26.818844) (xy 150.114 -36.089844) (xy 154.813 -40.788844) (xy 154.813 -49.635156)
				(xy 153.902156 -50.546) (xy 143.785844 -50.546) (xy 140.86459 -47.625) (xy 123.670822 -47.60976)
				(xy 106.15041 -47.625) (xy 104.372156 -49.403) (xy -8.459978 -49.38776) (xy -8.459978 -72.909938)
				(arc
					(start -0.350012 -72.909938)
					(mid 1.27 -74.52995)
					(end -0.350012 -76.149962)
				)
				(xy -8.459978 -76.149962) (xy -8.459978 -92.187014)
				(arc
					(start -0.999998 -92.187014)
					(mid 0.246641 -92.703389)
					(end 0.763016 -93.950028)
				)
				(arc
					(start 0.763016 -119.000016)
					(mid 0.832426 -119.167588)
					(end 0.999998 -119.236998)
				)
				(arc
					(start 161.660078 -119.236998)
					(mid 161.82765 -119.167588)
					(end 161.89706 -119.000016)
				)
				(arc
					(start 161.89706 -98.685096)
					(mid 161.869052 -98.573336)
					(end 161.79165 -98.487992)
				)
				(arc
					(start 159.488378 -96.952816)
					(mid 159.425669 -96.923162)
					(end 159.35706 -96.912938)
				)
				(arc
					(start 138.65987 -96.912938)
					(mid 137.413485 -96.396563)
					(end 136.89711 -95.150178)
				)
				(arc
					(start 136.89711 -90.849958)
					(mid 137.413485 -89.603319)
					(end 138.660124 -89.086944)
				)
				(arc
					(start 159.357314 -89.086944)
					(mid 159.425887 -89.076806)
					(end 159.488632 -89.04732)
				)
				(arc
					(start 161.79165 -87.512144)
					(mid 161.869054 -87.4268)
					(end 161.89706 -87.31504)
				)
				(arc
					(start 161.89706 -81.46288)
					(mid 161.82765 -81.295308)
					(end 161.660078 -81.225898)
				)
				(arc
					(start 158.65983 -81.225898)
					(mid 157.413445 -80.709523)
					(end 156.89707 -79.463138)
				)
				(arc
					(start 156.89707 -34.536888)
					(mid 157.413445 -33.290249)
					(end 158.660084 -32.773874)
				)
				(arc
					(start 161.660078 -32.773874)
					(mid 161.82765 -32.704464)
					(end 161.89706 -32.536892)
				)
				(arc
					(start 161.89706 -0.999998)
					(mid 161.82765 -0.832426)
					(end 161.660078 -0.763016)
				)
			)
		)
	)
)
